(kicad_sch
	(version 20250114)
	(generator "eeschema")
	(generator_version "9.0")
	(paper "A3")
	(title_block
		(title "SO-DIMM DDR5 Tester")
		(date "2025-11-26")
		(rev "1.3.0")
		(company "Antmicro Ltd.")
		(comment 1 "www.antmicro.com")
		(comment 2 "Antmicro Ltd")
	)
	(text "Not populated"
		(exclude_from_sim no)
		(at 285.115 108.585 0)
		(effects
			(font
				(size 1.27 1.27)
			)
			(justify left bottom)
		)
	)
	(text "0"
		(exclude_from_sim no)
		(at 309.245 111.76 0)
		(effects
			(font
				(size 1.27 1.27)
			)
			(justify left bottom)
		)
	)
	(text "1"
		(exclude_from_sim no)
		(at 324.485 108.585 0)
		(effects
			(font
				(size 1.27 1.27)
			)
			(justify left bottom)
		)
	)
	(text "Antmicro Testbed"
		(exclude_from_sim no)
		(at 285.115 114.935 0)
		(effects
			(font
				(size 1.27 1.27)
			)
			(justify left bottom)
		)
	)
	(text "Optional RFU"
		(exclude_from_sim no)
		(at 344.805 97.155 0)
		(effects
			(font
				(size 1.27 1.27)
			)
			(justify left bottom)
		)
	)
	(text "TB_DETECT"
		(exclude_from_sim no)
		(at 320.04 105.41 0)
		(effects
			(font
				(size 1.27 1.27)
			)
			(justify left bottom)
		)
	)
	(text "DDR5 SO-DIMM"
		(exclude_from_sim no)
		(at 285.115 111.76 0)
		(effects
			(font
				(size 1.27 1.27)
			)
			(justify left bottom)
		)
	)
	(text "Subchannel B"
		(exclude_from_sim no)
		(at 137.795 26.67 0)
		(effects
			(font
				(size 1.27 1.27)
			)
			(justify left bottom)
		)
	)
	(text "DDR5 SODIM connector"
		(exclude_from_sim no)
		(at 13.97 18.415 0)
		(effects
			(font
				(size 2.54 2.54)
				(thickness 0.5994)
				(bold yes)
			)
			(justify left bottom)
		)
	)
	(text "Power and control"
		(exclude_from_sim no)
		(at 247.65 26.67 0)
		(effects
			(font
				(size 1.27 1.27)
			)
			(justify left bottom)
		)
	)
	(text "HOT SWAP status LED"
		(exclude_from_sim no)
		(at 15.875 189.865 0)
		(effects
			(font
				(size 1.27 1.27)
				(thickness 0.254)
				(bold yes)
			)
			(justify left bottom)
		)
	)
	(text "HOT SWAP eject button"
		(exclude_from_sim no)
		(at 137.16 189.865 0)
		(effects
			(font
				(size 1.27 1.27)
				(thickness 0.254)
				(bold yes)
			)
			(justify left bottom)
		)
	)
	(text "1"
		(exclude_from_sim no)
		(at 324.485 114.935 0)
		(effects
			(font
				(size 1.27 1.27)
			)
			(justify left bottom)
		)
	)
	(text "Default 000"
		(exclude_from_sim no)
		(at 243.84 191.77 0)
		(effects
			(font
				(size 1.27 1.27)
			)
			(justify left bottom)
		)
	)
	(text "0"
		(exclude_from_sim no)
		(at 324.485 111.76 0)
		(effects
			(font
				(size 1.27 1.27)
			)
			(justify left bottom)
		)
	)
	(text "Plane decoupling"
		(exclude_from_sim no)
		(at 307.975 189.865 0)
		(effects
			(font
				(size 1.27 1.27)
				(thickness 0.254)
				(bold yes)
			)
			(justify left bottom)
		)
	)
	(text "~{DDR_PRESENCE}"
		(exclude_from_sim no)
		(at 302.895 105.41 0)
		(effects
			(font
				(size 1.27 1.27)
			)
			(justify left bottom)
		)
	)
	(text "Serial adress select"
		(exclude_from_sim no)
		(at 243.84 189.23 0)
		(effects
			(font
				(size 1.27 1.27)
				(thickness 0.254)
				(bold yes)
			)
			(justify left bottom)
		)
	)
	(text "Optional RC filter, tr=10ms"
		(exclude_from_sim no)
		(at 174.625 229.235 0)
		(effects
			(font
				(size 1.27 1.27)
			)
			(justify left bottom)
		)
	)
	(text "Subchannel A"
		(exclude_from_sim no)
		(at 19.685 26.67 0)
		(effects
			(font
				(size 1.27 1.27)
			)
			(justify left bottom)
		)
	)
	(text "0"
		(exclude_from_sim no)
		(at 309.245 114.935 0)
		(effects
			(font
				(size 1.27 1.27)
			)
			(justify left bottom)
		)
	)
	(text "1"
		(exclude_from_sim no)
		(at 309.245 108.585 0)
		(effects
			(font
				(size 1.27 1.27)
			)
			(justify left bottom)
		)
	)
	(text "SO-DIMM type detect"
		(exclude_from_sim no)
		(at 253.365 100.33 0)
		(effects
			(font
				(size 1.27 1.27)
			)
			(justify left bottom)
		)
	)
	(junction
		(at 278.13 52.705)
		(diameter 0)
		(color 0 0 0 0)
	)
	(junction
		(at 164.465 214.63)
		(diameter 0)
		(color 0 0 0 0)
	)
	(junction
		(at 267.97 52.705)
		(diameter 0)
		(color 0 0 0 0)
	)
	(junction
		(at 164.465 231.14)
		(diameter 0)
		(color 0 0 0 0)
	)
	(junction
		(at 266.065 123.825)
		(diameter 0)
		(color 0 0 0 0)
	)
	(junction
		(at 266.065 109.22)
		(diameter 0)
		(color 0 0 0 0)
	)
	(junction
		(at 359.41 121.92)
		(diameter 0)
		(color 0 0 0 0)
	)
	(junction
		(at 271.78 120.65)
		(diameter 0)
		(color 0 0 0 0)
	)
	(junction
		(at 353.695 126.365)
		(diameter 0)
		(color 0 0 0 0)
	)
	(junction
		(at 284.48 87.63)
		(diameter 0)
		(color 0 0 0 0)
	)
	(junction
		(at 364.49 117.475)
		(diameter 0)
		(color 0 0 0 0)
	)
	(junction
		(at 172.72 214.63)
		(diameter 0)
		(color 0 0 0 0)
	)
	(bus_entry
		(at 46.99 83.82)
		(size 2.54 2.54)
		(stroke
			(width 0)
			(type default)
		)
	)
	(bus_entry
		(at 213.36 58.42)
		(size 2.54 -2.54)
		(stroke
			(width 0)
			(type default)
		)
	)
	(bus_entry
		(at 213.36 146.05)
		(size 2.54 -2.54)
		(stroke
			(width 0)
			(type default)
		)
	)
	(bus_entry
		(at 154.94 60.96)
		(size 2.54 2.54)
		(stroke
			(width 0)
			(type default)
		)
	)
	(bus_entry
		(at 105.41 137.16)
		(size 2.54 -2.54)
		(stroke
			(width 0)
			(type default)
		)
	)
	(bus_entry
		(at 105.41 53.34)
		(size 2.54 -2.54)
		(stroke
			(width 0)
			(type default)
		)
	)
	(bus_entry
		(at 213.36 154.94)
		(size 2.54 -2.54)
		(stroke
			(width 0)
			(type default)
		)
	)
	(bus_entry
		(at 46.99 91.44)
		(size 2.54 2.54)
		(stroke
			(width 0)
			(type default)
		)
	)
	(bus_entry
		(at 213.36 165.1)
		(size 2.54 -2.54)
		(stroke
			(width 0)
			(type default)
		)
	)
	(bus_entry
		(at 105.41 104.14)
		(size 2.54 -2.54)
		(stroke
			(width 0)
			(type default)
		)
	)
	(bus_entry
		(at 105.41 124.46)
		(size 2.54 -2.54)
		(stroke
			(width 0)
			(type default)
		)
	)
	(bus_entry
		(at 154.94 91.44)
		(size 2.54 2.54)
		(stroke
			(width 0)
			(type default)
		)
	)
	(bus_entry
		(at 105.41 152.4)
		(size 2.54 -2.54)
		(stroke
			(width 0)
			(type default)
		)
	)
	(bus_entry
		(at 46.99 116.84)
		(size 2.54 2.54)
		(stroke
			(width 0)
			(type default)
		)
	)
	(bus_entry
		(at 213.36 93.98)
		(size 2.54 -2.54)
		(stroke
			(width 0)
			(type default)
		)
	)
	(bus_entry
		(at 213.36 80.01)
		(size 2.54 -2.54)
		(stroke
			(width 0)
			(type default)
		)
	)
	(bus_entry
		(at 46.99 44.45)
		(size 2.54 2.54)
		(stroke
			(width 0)
			(type default)
		)
	)
	(bus_entry
		(at 213.36 113.03)
		(size 2.54 -2.54)
		(stroke
			(width 0)
			(type default)
		)
	)
	(bus_entry
		(at 154.94 91.44)
		(size 2.54 2.54)
		(stroke
			(width 0)
			(type default)
		)
	)
	(bus_entry
		(at 154.94 119.38)
		(size 2.54 2.54)
		(stroke
			(width 0)
			(type default)
		)
	)
	(bus_entry
		(at 46.99 46.99)
		(size 2.54 2.54)
		(stroke
			(width 0)
			(type default)
		)
	)
	(bus_entry
		(at 105.41 107.95)
		(size 2.54 -2.54)
		(stroke
			(width 0)
			(type default)
		)
	)
	(bus_entry
		(at 105.41 170.18)
		(size 2.54 -2.54)
		(stroke
			(width 0)
			(type default)
		)
	)
	(bus_entry
		(at 154.94 68.58)
		(size 2.54 2.54)
		(stroke
			(width 0)
			(type default)
		)
	)
	(bus_entry
		(at 213.36 152.4)
		(size 2.54 -2.54)
		(stroke
			(width 0)
			(type default)
		)
	)
	(bus_entry
		(at 213.36 140.97)
		(size 2.54 -2.54)
		(stroke
			(width 0)
			(type default)
		)
	)
	(bus_entry
		(at 46.99 119.38)
		(size 2.54 2.54)
		(stroke
			(width 0)
			(type default)
		)
	)
	(bus_entry
		(at 154.94 88.9)
		(size 2.54 2.54)
		(stroke
			(width 0)
			(type default)
		)
	)
	(bus_entry
		(at 213.36 86.36)
		(size 2.54 -2.54)
		(stroke
			(width 0)
			(type default)
		)
	)
	(bus_entry
		(at 105.41 63.5)
		(size 2.54 -2.54)
		(stroke
			(width 0)
			(type default)
		)
	)
	(bus_entry
		(at 326.39 80.01)
		(size 2.54 -2.54)
		(stroke
			(width 0)
			(type default)
		)
	)
	(bus_entry
		(at 154.94 111.76)
		(size 2.54 2.54)
		(stroke
			(width 0)
			(type default)
		)
	)
	(bus_entry
		(at 154.94 73.66)
		(size 2.54 2.54)
		(stroke
			(width 0)
			(type default)
		)
	)
	(bus_entry
		(at 213.36 127)
		(size 2.54 -2.54)
		(stroke
			(width 0)
			(type default)
		)
	)
	(bus_entry
		(at 105.41 157.48)
		(size 2.54 -2.54)
		(stroke
			(width 0)
			(type default)
		)
	)
	(bus_entry
		(at 105.41 165.1)
		(size 2.54 -2.54)
		(stroke
			(width 0)
			(type default)
		)
	)
	(bus_entry
		(at 105.41 167.64)
		(size 2.54 -2.54)
		(stroke
			(width 0)
			(type default)
		)
	)
	(bus_entry
		(at 46.99 78.74)
		(size 2.54 2.54)
		(stroke
			(width 0)
			(type default)
		)
	)
	(bus_entry
		(at 213.36 121.92)
		(size 2.54 -2.54)
		(stroke
			(width 0)
			(type default)
		)
	)
	(bus_entry
		(at 154.94 53.34)
		(size 2.54 2.54)
		(stroke
			(width 0)
			(type default)
		)
	)
	(bus_entry
		(at 46.99 93.98)
		(size 2.54 2.54)
		(stroke
			(width 0)
			(type default)
		)
	)
	(bus_entry
		(at 154.94 116.84)
		(size 2.54 2.54)
		(stroke
			(width 0)
			(type default)
		)
	)
	(bus_entry
		(at 105.41 101.6)
		(size 2.54 -2.54)
		(stroke
			(width 0)
			(type default)
		)
	)
	(bus_entry
		(at 213.36 101.6)
		(size 2.54 -2.54)
		(stroke
			(width 0)
			(type default)
		)
	)
	(bus_entry
		(at 105.41 154.94)
		(size 2.54 -2.54)
		(stroke
			(width 0)
			(type default)
		)
	)
	(bus_entry
		(at 105.41 82.55)
		(size 2.54 -2.54)
		(stroke
			(width 0)
			(type default)
		)
	)
	(bus_entry
		(at 213.36 96.52)
		(size 2.54 -2.54)
		(stroke
			(width 0)
			(type default)
		)
	)
	(bus_entry
		(at 154.94 96.52)
		(size 2.54 2.54)
		(stroke
			(width 0)
			(type default)
		)
	)
	(bus_entry
		(at 213.36 124.46)
		(size 2.54 -2.54)
		(stroke
			(width 0)
			(type default)
		)
	)
	(bus_entry
		(at 154.94 78.74)
		(size 2.54 2.54)
		(stroke
			(width 0)
			(type default)
		)
	)
	(bus_entry
		(at 105.41 132.08)
		(size 2.54 -2.54)
		(stroke
			(width 0)
			(type default)
		)
	)
	(bus_entry
		(at 213.36 74.93)
		(size 2.54 -2.54)
		(stroke
			(width 0)
			(type default)
		)
	)
	(bus_entry
		(at 105.41 86.36)
		(size 2.54 -2.54)
		(stroke
			(width 0)
			(type default)
		)
	)
	(bus_entry
		(at 154.94 66.04)
		(size 2.54 2.54)
		(stroke
			(width 0)
			(type default)
		)
	)
	(bus_entry
		(at 213.36 104.14)
		(size 2.54 -2.54)
		(stroke
			(width 0)
			(type default)
		)
	)
	(bus_entry
		(at 46.99 66.04)
		(size 2.54 2.54)
		(stroke
			(width 0)
			(type default)
		)
	)
	(bus_entry
		(at 105.41 160.02)
		(size 2.54 -2.54)
		(stroke
			(width 0)
			(type default)
		)
	)
	(bus_entry
		(at 105.41 129.54)
		(size 2.54 -2.54)
		(stroke
			(width 0)
			(type default)
		)
	)
	(bus_entry
		(at 105.41 173.99)
		(size 2.54 -2.54)
		(stroke
			(width 0)
			(type default)
		)
	)
	(bus_entry
		(at 213.36 91.44)
		(size 2.54 -2.54)
		(stroke
			(width 0)
			(type default)
		)
	)
	(bus_entry
		(at 356.87 71.12)
		(size 2.54 -2.54)
		(stroke
			(width 0)
			(type default)
		)
	)
	(bus_entry
		(at 105.41 113.03)
		(size 2.54 -2.54)
		(stroke
			(width 0)
			(type default)
		)
	)
	(bus_entry
		(at 46.99 96.52)
		(size 2.54 2.54)
		(stroke
			(width 0)
			(type default)
		)
	)
	(bus_entry
		(at 46.99 53.34)
		(size 2.54 2.54)
		(stroke
			(width 0)
			(type default)
		)
	)
	(bus_entry
		(at 356.87 68.58)
		(size 2.54 -2.54)
		(stroke
			(width 0)
			(type default)
		)
	)
	(bus_entry
		(at 46.99 50.8)
		(size 2.54 2.54)
		(stroke
			(width 0)
			(type default)
		)
	)
	(bus_entry
		(at 105.41 115.57)
		(size 2.54 -2.54)
		(stroke
			(width 0)
			(type default)
		)
	)
	(bus_entry
		(at 105.41 99.06)
		(size 2.54 -2.54)
		(stroke
			(width 0)
			(type default)
		)
	)
	(bus_entry
		(at 213.36 66.04)
		(size 2.54 -2.54)
		(stroke
			(width 0)
			(type default)
		)
	)
	(bus_entry
		(at 213.36 132.08)
		(size 2.54 -2.54)
		(stroke
			(width 0)
			(type default)
		)
	)
	(bus_entry
		(at 105.41 121.92)
		(size 2.54 -2.54)
		(stroke
			(width 0)
			(type default)
		)
	)
	(bus_entry
		(at 46.99 86.36)
		(size 2.54 2.54)
		(stroke
			(width 0)
			(type default)
		)
	)
	(bus_entry
		(at 356.87 73.66)
		(size 2.54 -2.54)
		(stroke
			(width 0)
			(type default)
		)
	)
	(bus_entry
		(at 46.99 104.14)
		(size 2.54 2.54)
		(stroke
			(width 0)
			(type default)
		)
	)
	(bus_entry
		(at 154.94 71.12)
		(size 2.54 2.54)
		(stroke
			(width 0)
			(type default)
		)
	)
	(bus_entry
		(at 154.94 81.28)
		(size 2.54 2.54)
		(stroke
			(width 0)
			(type default)
		)
	)
	(bus_entry
		(at 46.99 73.66)
		(size 2.54 2.54)
		(stroke
			(width 0)
			(type default)
		)
	)
	(bus_entry
		(at 154.94 50.8)
		(size 2.54 2.54)
		(stroke
			(width 0)
			(type default)
		)
	)
	(bus_entry
		(at 213.36 88.9)
		(size 2.54 -2.54)
		(stroke
			(width 0)
			(type default)
		)
	)
	(bus_entry
		(at 154.94 46.99)
		(size 2.54 2.54)
		(stroke
			(width 0)
			(type default)
		)
	)
	(bus_entry
		(at 213.36 46.99)
		(size 2.54 -2.54)
		(stroke
			(width 0)
			(type default)
		)
	)
	(bus_entry
		(at 105.41 58.42)
		(size 2.54 -2.54)
		(stroke
			(width 0)
			(type default)
		)
	)
	(bus_entry
		(at 46.99 106.68)
		(size 2.54 2.54)
		(stroke
			(width 0)
			(type default)
		)
	)
	(bus_entry
		(at 154.94 114.3)
		(size 2.54 2.54)
		(stroke
			(width 0)
			(type default)
		)
	)
	(bus_entry
		(at 105.41 162.56)
		(size 2.54 -2.54)
		(stroke
			(width 0)
			(type default)
		)
	)
	(bus_entry
		(at 105.41 127)
		(size 2.54 -2.54)
		(stroke
			(width 0)
			(type default)
		)
	)
	(bus_entry
		(at 213.36 160.02)
		(size 2.54 -2.54)
		(stroke
			(width 0)
			(type default)
		)
	)
	(bus_entry
		(at 105.41 93.98)
		(size 2.54 -2.54)
		(stroke
			(width 0)
			(type default)
		)
	)
	(bus_entry
		(at 105.41 146.05)
		(size 2.54 -2.54)
		(stroke
			(width 0)
			(type default)
		)
	)
	(bus_entry
		(at 213.36 173.99)
		(size 2.54 -2.54)
		(stroke
			(width 0)
			(type default)
		)
	)
	(bus_entry
		(at 105.41 68.58)
		(size 2.54 -2.54)
		(stroke
			(width 0)
			(type default)
		)
	)
	(bus_entry
		(at 213.36 157.48)
		(size 2.54 -2.54)
		(stroke
			(width 0)
			(type default)
		)
	)
	(bus_entry
		(at 213.36 115.57)
		(size 2.54 -2.54)
		(stroke
			(width 0)
			(type default)
		)
	)
	(bus_entry
		(at 213.36 68.58)
		(size 2.54 -2.54)
		(stroke
			(width 0)
			(type default)
		)
	)
	(bus_entry
		(at 46.99 58.42)
		(size 2.54 2.54)
		(stroke
			(width 0)
			(type default)
		)
	)
	(bus_entry
		(at 154.94 76.2)
		(size 2.54 2.54)
		(stroke
			(width 0)
			(type default)
		)
	)
	(bus_entry
		(at 356.87 66.04)
		(size 2.54 -2.54)
		(stroke
			(width 0)
			(type default)
		)
	)
	(bus_entry
		(at 46.99 71.12)
		(size 2.54 2.54)
		(stroke
			(width 0)
			(type default)
		)
	)
	(bus_entry
		(at 213.36 53.34)
		(size 2.54 -2.54)
		(stroke
			(width 0)
			(type default)
		)
	)
	(bus_entry
		(at 105.41 71.12)
		(size 2.54 -2.54)
		(stroke
			(width 0)
			(type default)
		)
	)
	(bus_entry
		(at 154.94 104.14)
		(size 2.54 2.54)
		(stroke
			(width 0)
			(type default)
		)
	)
	(bus_entry
		(at 213.36 63.5)
		(size 2.54 -2.54)
		(stroke
			(width 0)
			(type default)
		)
	)
	(bus_entry
		(at 105.41 134.62)
		(size 2.54 -2.54)
		(stroke
			(width 0)
			(type default)
		)
	)
	(bus_entry
		(at 213.36 119.38)
		(size 2.54 -2.54)
		(stroke
			(width 0)
			(type default)
		)
	)
	(bus_entry
		(at 213.36 49.53)
		(size 2.54 -2.54)
		(stroke
			(width 0)
			(type default)
		)
	)
	(bus_entry
		(at 154.94 86.36)
		(size 2.54 2.54)
		(stroke
			(width 0)
			(type default)
		)
	)
	(bus_entry
		(at 213.36 99.06)
		(size 2.54 -2.54)
		(stroke
			(width 0)
			(type default)
		)
	)
	(bus_entry
		(at 46.99 91.44)
		(size 2.54 2.54)
		(stroke
			(width 0)
			(type default)
		)
	)
	(bus_entry
		(at 154.94 106.68)
		(size 2.54 2.54)
		(stroke
			(width 0)
			(type default)
		)
	)
	(bus_entry
		(at 105.41 96.52)
		(size 2.54 -2.54)
		(stroke
			(width 0)
			(type default)
		)
	)
	(bus_entry
		(at 213.36 170.18)
		(size 2.54 -2.54)
		(stroke
			(width 0)
			(type default)
		)
	)
	(bus_entry
		(at 213.36 134.62)
		(size 2.54 -2.54)
		(stroke
			(width 0)
			(type default)
		)
	)
	(bus_entry
		(at 105.41 55.88)
		(size 2.54 -2.54)
		(stroke
			(width 0)
			(type default)
		)
	)
	(bus_entry
		(at 46.99 111.76)
		(size 2.54 2.54)
		(stroke
			(width 0)
			(type default)
		)
	)
	(bus_entry
		(at 105.41 66.04)
		(size 2.54 -2.54)
		(stroke
			(width 0)
			(type default)
		)
	)
	(bus_entry
		(at 213.36 107.95)
		(size 2.54 -2.54)
		(stroke
			(width 0)
			(type default)
		)
	)
	(bus_entry
		(at 105.41 148.59)
		(size 2.54 -2.54)
		(stroke
			(width 0)
			(type default)
		)
	)
	(bus_entry
		(at 213.36 137.16)
		(size 2.54 -2.54)
		(stroke
			(width 0)
			(type default)
		)
	)
	(bus_entry
		(at 213.36 148.59)
		(size 2.54 -2.54)
		(stroke
			(width 0)
			(type default)
		)
	)
	(bus_entry
		(at 154.94 83.82)
		(size 2.54 2.54)
		(stroke
			(width 0)
			(type default)
		)
	)
	(bus_entry
		(at 213.36 82.55)
		(size 2.54 -2.54)
		(stroke
			(width 0)
			(type default)
		)
	)
	(bus_entry
		(at 105.41 49.53)
		(size 2.54 -2.54)
		(stroke
			(width 0)
			(type default)
		)
	)
	(bus_entry
		(at 105.41 74.93)
		(size 2.54 -2.54)
		(stroke
			(width 0)
			(type default)
		)
	)
	(bus_entry
		(at 105.41 91.44)
		(size 2.54 -2.54)
		(stroke
			(width 0)
			(type default)
		)
	)
	(bus_entry
		(at 105.41 119.38)
		(size 2.54 -2.54)
		(stroke
			(width 0)
			(type default)
		)
	)
	(bus_entry
		(at 154.94 58.42)
		(size 2.54 2.54)
		(stroke
			(width 0)
			(type default)
		)
	)
	(bus_entry
		(at 46.99 68.58)
		(size 2.54 2.54)
		(stroke
			(width 0)
			(type default)
		)
	)
	(bus_entry
		(at 213.36 167.64)
		(size 2.54 -2.54)
		(stroke
			(width 0)
			(type default)
		)
	)
	(bus_entry
		(at 46.99 114.3)
		(size 2.54 2.54)
		(stroke
			(width 0)
			(type default)
		)
	)
	(bus_entry
		(at 46.99 88.9)
		(size 2.54 2.54)
		(stroke
			(width 0)
			(type default)
		)
	)
	(bus_entry
		(at 213.36 60.96)
		(size 2.54 -2.54)
		(stroke
			(width 0)
			(type default)
		)
	)
	(bus_entry
		(at 213.36 129.54)
		(size 2.54 -2.54)
		(stroke
			(width 0)
			(type default)
		)
	)
	(bus_entry
		(at 105.41 140.97)
		(size 2.54 -2.54)
		(stroke
			(width 0)
			(type default)
		)
	)
	(bus_entry
		(at 154.94 93.98)
		(size 2.54 2.54)
		(stroke
			(width 0)
			(type default)
		)
	)
	(bus_entry
		(at 46.99 60.96)
		(size 2.54 2.54)
		(stroke
			(width 0)
			(type default)
		)
	)
	(bus_entry
		(at 213.36 162.56)
		(size 2.54 -2.54)
		(stroke
			(width 0)
			(type default)
		)
	)
	(bus_entry
		(at 154.94 44.45)
		(size 2.54 2.54)
		(stroke
			(width 0)
			(type default)
		)
	)
	(bus_entry
		(at 105.41 60.96)
		(size 2.54 -2.54)
		(stroke
			(width 0)
			(type default)
		)
	)
	(bus_entry
		(at 326.39 82.55)
		(size 2.54 -2.54)
		(stroke
			(width 0)
			(type default)
		)
	)
	(bus_entry
		(at 105.41 80.01)
		(size 2.54 -2.54)
		(stroke
			(width 0)
			(type default)
		)
	)
	(bus_entry
		(at 213.36 55.88)
		(size 2.54 -2.54)
		(stroke
			(width 0)
			(type default)
		)
	)
	(bus_entry
		(at 105.41 46.99)
		(size 2.54 -2.54)
		(stroke
			(width 0)
			(type default)
		)
	)
	(bus_entry
		(at 46.99 76.2)
		(size 2.54 2.54)
		(stroke
			(width 0)
			(type default)
		)
	)
	(bus_entry
		(at 46.99 81.28)
		(size 2.54 2.54)
		(stroke
			(width 0)
			(type default)
		)
	)
	(bus_entry
		(at 213.36 71.12)
		(size 2.54 -2.54)
		(stroke
			(width 0)
			(type default)
		)
	)
	(bus_entry
		(at 105.41 88.9)
		(size 2.54 -2.54)
		(stroke
			(width 0)
			(type default)
		)
	)
	(polyline
		(pts
			(xy 302.26 102.87) (xy 302.26 114.935)
		)
		(stroke
			(width 0)
			(type default)
		)
	)
	(bus
		(pts
			(xy 107.95 157.48) (xy 107.95 160.02)
		)
		(stroke
			(width 0)
			(type default)
		)
	)
	(wire
		(pts
			(xy 266.065 109.22) (xy 266.065 111.125)
		)
		(stroke
			(width 0)
			(type default)
		)
	)
	(wire
		(pts
			(xy 344.805 121.92) (xy 359.41 121.92)
		)
		(stroke
			(width 0)
			(type default)
		)
	)
	(bus
		(pts
			(xy 215.9 101.6) (xy 215.9 105.41)
		)
		(stroke
			(width 0)
			(type default)
		)
	)
	(wire
		(pts
			(xy 105.41 165.1) (xy 95.25 165.1)
		)
		(stroke
			(width 0)
			(type default)
		)
	)
	(wire
		(pts
			(xy 105.41 71.12) (xy 95.25 71.12)
		)
		(stroke
			(width 0)
			(type default)
		)
	)
	(wire
		(pts
			(xy 67.31 217.17) (xy 67.31 238.76)
		)
		(stroke
			(width 0)
			(type default)
		)
	)
	(wire
		(pts
			(xy 353.695 126.365) (xy 353.695 131.445)
		)
		(stroke
			(width 0)
			(type default)
		)
	)
	(bus
		(pts
			(xy 107.95 143.51) (xy 107.95 146.05)
		)
		(stroke
			(width 0)
			(type default)
		)
	)
	(wire
		(pts
			(xy 284.48 85.09) (xy 288.29 85.09)
		)
		(stroke
			(width 0)
			(type default)
		)
	)
	(wire
		(pts
			(xy 105.41 86.36) (xy 95.25 86.36)
		)
		(stroke
			(width 0)
			(type default)
		)
	)
	(wire
		(pts
			(xy 157.48 78.74) (xy 167.64 78.74)
		)
		(stroke
			(width 0)
			(type default)
		)
	)
	(wire
		(pts
			(xy 59.69 119.38) (xy 49.53 119.38)
		)
		(stroke
			(width 0)
			(type default)
		)
	)
	(wire
		(pts
			(xy 213.36 162.56) (xy 203.2 162.56)
		)
		(stroke
			(width 0)
			(type default)
		)
	)
	(wire
		(pts
			(xy 157.48 99.06) (xy 167.64 99.06)
		)
		(stroke
			(width 0)
			(type default)
		)
	)
	(wire
		(pts
			(xy 271.78 111.125) (xy 271.78 109.22)
		)
		(stroke
			(width 0)
			(type default)
		)
	)
	(wire
		(pts
			(xy 213.36 146.05) (xy 203.2 146.05)
		)
		(stroke
			(width 0)
			(type default)
		)
	)
	(wire
		(pts
			(xy 105.41 152.4) (xy 95.25 152.4)
		)
		(stroke
			(width 0)
			(type default)
		)
	)
	(bus
		(pts
			(xy 215.9 77.47) (xy 215.9 80.01)
		)
		(stroke
			(width 0)
			(type default)
		)
	)
	(wire
		(pts
			(xy 267.97 52.705) (xy 267.97 54.61)
		)
		(stroke
			(width 0)
			(type default)
		)
	)
	(wire
		(pts
			(xy 266.065 123.825) (xy 275.59 123.825)
		)
		(stroke
			(width 0)
			(type default)
		)
	)
	(wire
		(pts
			(xy 36.83 207.01) (xy 41.91 207.01)
		)
		(stroke
			(width 0)
			(type default)
		)
	)
	(bus
		(pts
			(xy 107.95 93.98) (xy 107.95 96.52)
		)
		(stroke
			(width 0)
			(type default)
		)
	)
	(wire
		(pts
			(xy 49.53 49.53) (xy 59.69 49.53)
		)
		(stroke
			(width 0)
			(type default)
		)
	)
	(wire
		(pts
			(xy 105.41 91.44) (xy 95.25 91.44)
		)
		(stroke
			(width 0)
			(type default)
		)
	)
	(wire
		(pts
			(xy 157.48 68.58) (xy 167.64 68.58)
		)
		(stroke
			(width 0)
			(type default)
		)
	)
	(wire
		(pts
			(xy 49.53 96.52) (xy 59.69 96.52)
		)
		(stroke
			(width 0)
			(type default)
		)
	)
	(bus
		(pts
			(xy 107.95 129.54) (xy 107.95 132.08)
		)
		(stroke
			(width 0)
			(type default)
		)
	)
	(wire
		(pts
			(xy 167.64 119.38) (xy 157.48 119.38)
		)
		(stroke
			(width 0)
			(type default)
		)
	)
	(wire
		(pts
			(xy 267.97 51.435) (xy 267.97 52.705)
		)
		(stroke
			(width 0)
			(type default)
		)
	)
	(bus
		(pts
			(xy 215.9 99.06) (xy 215.9 101.6)
		)
		(stroke
			(width 0)
			(type default)
		)
	)
	(wire
		(pts
			(xy 286.385 52.705) (xy 286.385 66.04)
		)
		(stroke
			(width 0)
			(type default)
		)
	)
	(wire
		(pts
			(xy 105.41 170.18) (xy 95.25 170.18)
		)
		(stroke
			(width 0)
			(type default)
		)
	)
	(bus
		(pts
			(xy 110.49 42.545) (xy 108.585 42.545)
		)
		(stroke
			(width 0)
			(type default)
		)
	)
	(wire
		(pts
			(xy 105.41 173.99) (xy 95.25 173.99)
		)
		(stroke
			(width 0)
			(type default)
		)
	)
	(wire
		(pts
			(xy 271.78 120.65) (xy 271.78 129.54)
		)
		(stroke
			(width 0)
			(type default)
		)
	)
	(wire
		(pts
			(xy 213.36 104.14) (xy 203.2 104.14)
		)
		(stroke
			(width 0)
			(type default)
		)
	)
	(wire
		(pts
			(xy 157.48 109.22) (xy 167.64 109.22)
		)
		(stroke
			(width 0)
			(type default)
		)
	)
	(wire
		(pts
			(xy 164.465 214.63) (xy 172.72 214.63)
		)
		(stroke
			(width 0)
			(type default)
		)
	)
	(bus
		(pts
			(xy 215.9 80.01) (xy 215.9 83.82)
		)
		(stroke
			(width 0)
			(type default)
		)
	)
	(bus
		(pts
			(xy 154.94 86.36) (xy 154.94 88.9)
		)
		(stroke
			(width 0)
			(type default)
		)
	)
	(bus
		(pts
			(xy 215.9 121.92) (xy 215.9 124.46)
		)
		(stroke
			(width 0)
			(type default)
		)
	)
	(wire
		(pts
			(xy 213.36 96.52) (xy 203.2 96.52)
		)
		(stroke
			(width 0)
			(type default)
		)
	)
	(bus
		(pts
			(xy 218.44 42.545) (xy 216.535 42.545)
		)
		(stroke
			(width 0)
			(type default)
		)
	)
	(wire
		(pts
			(xy 275.59 120.65) (xy 271.78 120.65)
		)
		(stroke
			(width 0)
			(type default)
		)
	)
	(bus
		(pts
			(xy 215.9 160.02) (xy 215.9 162.56)
		)
		(stroke
			(width 0)
			(type default)
		)
	)
	(bus
		(pts
			(xy 215.9 124.46) (xy 215.9 127)
		)
		(stroke
			(width 0)
			(type default)
		)
	)
	(wire
		(pts
			(xy 167.64 116.84) (xy 157.48 116.84)
		)
		(stroke
			(width 0)
			(type default)
		)
	)
	(bus
		(pts
			(xy 154.94 60.96) (xy 154.94 66.04)
		)
		(stroke
			(width 0)
			(type default)
		)
	)
	(wire
		(pts
			(xy 105.41 167.64) (xy 95.25 167.64)
		)
		(stroke
			(width 0)
			(type default)
		)
	)
	(wire
		(pts
			(xy 267.97 52.705) (xy 278.13 52.705)
		)
		(stroke
			(width 0)
			(type default)
		)
	)
	(wire
		(pts
			(xy 351.155 224.79) (xy 351.155 223.52)
		)
		(stroke
			(width 0)
			(type default)
		)
	)
	(wire
		(pts
			(xy 105.41 119.38) (xy 95.25 119.38)
		)
		(stroke
			(width 0)
			(type default)
		)
	)
	(wire
		(pts
			(xy 356.87 68.58) (xy 316.23 68.58)
		)
		(stroke
			(width 0)
			(type default)
		)
	)
	(wire
		(pts
			(xy 172.72 214.63) (xy 172.72 220.345)
		)
		(stroke
			(width 0)
			(type default)
		)
	)
	(bus
		(pts
			(xy 359.41 68.58) (xy 359.41 71.12)
		)
		(stroke
			(width 0)
			(type default)
		)
	)
	(wire
		(pts
			(xy 213.36 60.96) (xy 203.2 60.96)
		)
		(stroke
			(width 0)
			(type default)
		)
	)
	(bus
		(pts
			(xy 215.9 127) (xy 215.9 129.54)
		)
		(stroke
			(width 0)
			(type default)
		)
	)
	(polyline
		(pts
			(xy 304.8 184.15) (xy 304.8 252.73)
		)
		(stroke
			(width 0)
			(type default)
		)
	)
	(wire
		(pts
			(xy 95.25 49.53) (xy 105.41 49.53)
		)
		(stroke
			(width 0)
			(type default)
		)
	)
	(wire
		(pts
			(xy 49.53 46.99) (xy 59.69 46.99)
		)
		(stroke
			(width 0)
			(type default)
		)
	)
	(wire
		(pts
			(xy 104.14 251.46) (xy 104.14 231.14)
		)
		(stroke
			(width 0)
			(type default)
		)
	)
	(bus
		(pts
			(xy 215.9 113.03) (xy 215.9 116.84)
		)
		(stroke
			(width 0)
			(type default)
		)
	)
	(wire
		(pts
			(xy 105.41 127) (xy 95.25 127)
		)
		(stroke
			(width 0)
			(type default)
		)
	)
	(wire
		(pts
			(xy 157.48 106.68) (xy 167.64 106.68)
		)
		(stroke
			(width 0)
			(type default)
		)
	)
	(wire
		(pts
			(xy 105.41 129.54) (xy 95.25 129.54)
		)
		(stroke
			(width 0)
			(type default)
		)
	)
	(wire
		(pts
			(xy 269.875 227.965) (xy 269.875 229.235)
		)
		(stroke
			(width 0)
			(type default)
		)
	)
	(bus
		(pts
			(xy 107.95 101.6) (xy 107.95 105.41)
		)
		(stroke
			(width 0)
			(type default)
		)
	)
	(wire
		(pts
			(xy 266.065 107.315) (xy 266.065 109.22)
		)
		(stroke
			(width 0)
			(type default)
		)
	)
	(wire
		(pts
			(xy 213.36 93.98) (xy 203.2 93.98)
		)
		(stroke
			(width 0)
			(type default)
		)
	)
	(wire
		(pts
			(xy 105.41 162.56) (xy 95.25 162.56)
		)
		(stroke
			(width 0)
			(type default)
		)
	)
	(wire
		(pts
			(xy 164.465 231.14) (xy 164.465 234.95)
		)
		(stroke
			(width 0)
			(type default)
		)
	)
	(bus
		(pts
			(xy 215.9 66.04) (xy 215.9 68.58)
		)
		(stroke
			(width 0)
			(type default)
		)
	)
	(bus
		(pts
			(xy 215.9 129.54) (xy 215.9 132.08)
		)
		(stroke
			(width 0)
			(type default)
		)
	)
	(bus
		(pts
			(xy 46.99 96.52) (xy 46.99 104.14)
		)
		(stroke
			(width 0)
			(type default)
		)
	)
	(wire
		(pts
			(xy 372.745 117.475) (xy 379.73 117.475)
		)
		(stroke
			(width 0)
			(type default)
		)
	)
	(wire
		(pts
			(xy 105.41 99.06) (xy 95.25 99.06)
		)
		(stroke
			(width 0)
			(type default)
		)
	)
	(wire
		(pts
			(xy 105.41 74.93) (xy 95.25 74.93)
		)
		(stroke
			(width 0)
			(type default)
		)
	)
	(wire
		(pts
			(xy 353.695 136.525) (xy 353.695 138.43)
		)
		(stroke
			(width 0)
			(type default)
		)
	)
	(wire
		(pts
			(xy 271.78 134.62) (xy 271.78 136.525)
		)
		(stroke
			(width 0)
			(type default)
		)
	)
	(wire
		(pts
			(xy 203.2 115.57) (xy 213.36 115.57)
		)
		(stroke
			(width 0)
			(type default)
		)
	)
	(wire
		(pts
			(xy 372.745 126.365) (xy 379.73 126.365)
		)
		(stroke
			(width 0)
			(type default)
		)
	)
	(wire
		(pts
			(xy 213.36 121.92) (xy 203.2 121.92)
		)
		(stroke
			(width 0)
			(type default)
		)
	)
	(wire
		(pts
			(xy 157.48 81.28) (xy 167.64 81.28)
		)
		(stroke
			(width 0)
			(type default)
		)
	)
	(wire
		(pts
			(xy 213.36 99.06) (xy 203.2 99.06)
		)
		(stroke
			(width 0)
			(type default)
		)
	)
	(wire
		(pts
			(xy 284.48 87.63) (xy 284.48 90.805)
		)
		(stroke
			(width 0)
			(type default)
		)
	)
	(wire
		(pts
			(xy 105.41 68.58) (xy 95.25 68.58)
		)
		(stroke
			(width 0)
			(type default)
		)
	)
	(bus
		(pts
			(xy 46.99 50.8) (xy 46.99 53.34)
		)
		(stroke
			(width 0)
			(type default)
		)
	)
	(wire
		(pts
			(xy 278.13 52.705) (xy 278.13 54.61)
		)
		(stroke
			(width 0)
			(type default)
		)
	)
	(wire
		(pts
			(xy 157.48 73.66) (xy 167.64 73.66)
		)
		(stroke
			(width 0)
			(type default)
		)
	)
	(bus
		(pts
			(xy 215.9 167.64) (xy 215.9 171.45)
		)
		(stroke
			(width 0)
			(type default)
		)
	)
	(bus
		(pts
			(xy 107.95 50.8) (xy 107.95 53.34)
		)
		(stroke
			(width 0)
			(type default)
		)
	)
	(wire
		(pts
			(xy 157.48 93.98) (xy 167.64 93.98)
		)
		(stroke
			(width 0)
			(type default)
		)
	)
	(wire
		(pts
			(xy 95.25 148.59) (xy 105.41 148.59)
		)
		(stroke
			(width 0)
			(type default)
		)
	)
	(bus
		(pts
			(xy 215.9 46.99) (xy 215.9 50.8)
		)
		(stroke
			(width 0)
			(type default)
		)
	)
	(wire
		(pts
			(xy 67.31 210.82) (xy 60.96 210.82)
		)
		(stroke
			(width 0)
			(type default)
		)
	)
	(wire
		(pts
			(xy 49.53 109.22) (xy 59.69 109.22)
		)
		(stroke
			(width 0)
			(type default)
		)
	)
	(wire
		(pts
			(xy 213.36 119.38) (xy 203.2 119.38)
		)
		(stroke
			(width 0)
			(type default)
		)
	)
	(wire
		(pts
			(xy 172.72 214.63) (xy 180.34 214.63)
		)
		(stroke
			(width 0)
			(type default)
		)
	)
	(bus
		(pts
			(xy 359.41 63.5) (xy 359.41 66.04)
		)
		(stroke
			(width 0)
			(type default)
		)
	)
	(bus
		(pts
			(xy 46.99 43.18) (xy 46.99 44.45)
		)
		(stroke
			(width 0)
			(type default)
		)
	)
	(wire
		(pts
			(xy 254 120.65) (xy 271.78 120.65)
		)
		(stroke
			(width 0)
			(type default)
		)
	)
	(bus
		(pts
			(xy 154.94 46.99) (xy 154.94 50.8)
		)
		(stroke
			(width 0)
			(type default)
		)
	)
	(bus
		(pts
			(xy 107.95 80.01) (xy 107.95 83.82)
		)
		(stroke
			(width 0)
			(type default)
		)
	)
	(wire
		(pts
			(xy 49.53 71.12) (xy 59.69 71.12)
		)
		(stroke
			(width 0)
			(type default)
		)
	)
	(wire
		(pts
			(xy 105.41 63.5) (xy 95.25 63.5)
		)
		(stroke
			(width 0)
			(type default)
		)
	)
	(wire
		(pts
			(xy 105.41 93.98) (xy 95.25 93.98)
		)
		(stroke
			(width 0)
			(type default)
		)
	)
	(wire
		(pts
			(xy 104.14 218.44) (xy 104.14 217.17)
		)
		(stroke
			(width 0)
			(type default)
		)
	)
	(bus
		(pts
			(xy 215.9 86.36) (xy 215.9 88.9)
		)
		(stroke
			(width 0)
			(type default)
		)
	)
	(wire
		(pts
			(xy 164.465 214.63) (xy 161.925 214.63)
		)
		(stroke
			(width 0)
			(type default)
		)
	)
	(bus
		(pts
			(xy 46.355 42.545) (xy 46.99 43.18)
		)
		(stroke
			(width 0)
			(type default)
		)
	)
	(bus
		(pts
			(xy 107.95 113.03) (xy 107.95 116.84)
		)
		(stroke
			(width 0)
			(type default)
		)
	)
	(bus
		(pts
			(xy 107.95 160.02) (xy 107.95 162.56)
		)
		(stroke
			(width 0)
			(type default)
		)
	)
	(wire
		(pts
			(xy 254 123.825) (xy 266.065 123.825)
		)
		(stroke
			(width 0)
			(type default)
		)
	)
	(wire
		(pts
			(xy 105.41 121.92) (xy 95.25 121.92)
		)
		(stroke
			(width 0)
			(type default)
		)
	)
	(wire
		(pts
			(xy 105.41 60.96) (xy 95.25 60.96)
		)
		(stroke
			(width 0)
			(type default)
		)
	)
	(wire
		(pts
			(xy 203.2 148.59) (xy 213.36 148.59)
		)
		(stroke
			(width 0)
			(type default)
		)
	)
	(bus
		(pts
			(xy 107.95 152.4) (xy 107.95 154.94)
		)
		(stroke
			(width 0)
			(type default)
		)
	)
	(bus
		(pts
			(xy 107.95 116.84) (xy 107.95 119.38)
		)
		(stroke
			(width 0)
			(type default)
		)
	)
	(bus
		(pts
			(xy 46.99 104.14) (xy 46.99 106.68)
		)
		(stroke
			(width 0)
			(type default)
		)
	)
	(bus
		(pts
			(xy 216.535 42.545) (xy 215.9 43.18)
		)
		(stroke
			(width 0)
			(type default)
		)
	)
	(wire
		(pts
			(xy 164.465 231.14) (xy 172.72 231.14)
		)
		(stroke
			(width 0)
			(type default)
		)
	)
	(wire
		(pts
			(xy 364.49 117.475) (xy 364.49 131.445)
		)
		(stroke
			(width 0)
			(type default)
		)
	)
	(wire
		(pts
			(xy 49.53 63.5) (xy 59.69 63.5)
		)
		(stroke
			(width 0)
			(type default)
		)
	)
	(wire
		(pts
			(xy 58.42 227.33) (xy 96.52 227.33)
		)
		(stroke
			(width 0)
			(type default)
		)
	)
	(wire
		(pts
			(xy 213.36 71.12) (xy 203.2 71.12)
		)
		(stroke
			(width 0)
			(type default)
		)
	)
	(wire
		(pts
			(xy 361.95 224.79) (xy 361.95 223.52)
		)
		(stroke
			(width 0)
			(type default)
		)
	)
	(wire
		(pts
			(xy 316.23 71.12) (xy 328.93 71.12)
		)
		(stroke
			(width 0)
			(type default)
		)
	)
	(bus
		(pts
			(xy 154.94 81.28) (xy 154.94 83.82)
		)
		(stroke
			(width 0)
			(type default)
		)
	)
	(wire
		(pts
			(xy 269.875 220.98) (xy 269.875 222.885)
		)
		(stroke
			(width 0)
			(type default)
		)
	)
	(bus
		(pts
			(xy 46.99 114.3) (xy 46.99 116.84)
		)
		(stroke
			(width 0)
			(type default)
		)
	)
	(bus
		(pts
			(xy 107.95 43.18) (xy 107.95 44.45)
		)
		(stroke
			(width 0)
			(type default)
		)
	)
	(wire
		(pts
			(xy 344.805 126.365) (xy 353.695 126.365)
		)
		(stroke
			(width 0)
			(type default)
		)
	)
	(bus
		(pts
			(xy 154.94 78.74) (xy 154.94 81.28)
		)
		(stroke
			(width 0)
			(type default)
		)
	)
	(wire
		(pts
			(xy 59.69 116.84) (xy 49.53 116.84)
		)
		(stroke
			(width 0)
			(type default)
		)
	)
	(wire
		(pts
			(xy 316.23 66.04) (xy 328.93 66.04)
		)
		(stroke
			(width 0)
			(type default)
		)
	)
	(bus
		(pts
			(xy 46.99 68.58) (xy 46.99 71.12)
		)
		(stroke
			(width 0)
			(type default)
		)
	)
	(wire
		(pts
			(xy 213.36 113.03) (xy 203.2 113.03)
		)
		(stroke
			(width 0)
			(type default)
		)
	)
	(bus
		(pts
			(xy 215.9 116.84) (xy 215.9 119.38)
		)
		(stroke
			(width 0)
			(type default)
		)
	)
	(wire
		(pts
			(xy 213.36 68.58) (xy 203.2 68.58)
		)
		(stroke
			(width 0)
			(type default)
		)
	)
	(wire
		(pts
			(xy 49.53 81.28) (xy 59.69 81.28)
		)
		(stroke
			(width 0)
			(type default)
		)
	)
	(wire
		(pts
			(xy 213.36 91.44) (xy 203.2 91.44)
		)
		(stroke
			(width 0)
			(type default)
		)
	)
	(wire
		(pts
			(xy 356.87 66.04) (xy 334.01 66.04)
		)
		(stroke
			(width 0)
			(type default)
		)
	)
	(wire
		(pts
			(xy 213.36 137.16) (xy 203.2 137.16)
		)
		(stroke
			(width 0)
			(type default)
		)
	)
	(wire
		(pts
			(xy 60.96 207.01) (xy 86.36 207.01)
		)
		(stroke
			(width 0)
			(type default)
		)
	)
	(bus
		(pts
			(xy 107.95 91.44) (xy 107.95 93.98)
		)
		(stroke
			(width 0)
			(type default)
		)
	)
	(bus
		(pts
			(xy 215.9 93.98) (xy 215.9 96.52)
		)
		(stroke
			(width 0)
			(type default)
		)
	)
	(bus
		(pts
			(xy 215.9 91.44) (xy 215.9 93.98)
		)
		(stroke
			(width 0)
			(type default)
		)
	)
	(bus
		(pts
			(xy 107.95 154.94) (xy 107.95 157.48)
		)
		(stroke
			(width 0)
			(type default)
		)
	)
	(bus
		(pts
			(xy 107.95 149.86) (xy 107.95 152.4)
		)
		(stroke
			(width 0)
			(type default)
		)
	)
	(bus
		(pts
			(xy 46.99 46.99) (xy 46.99 50.8)
		)
		(stroke
			(width 0)
			(type default)
		)
	)
	(wire
		(pts
			(xy 271.78 109.22) (xy 266.065 109.22)
		)
		(stroke
			(width 0)
			(type default)
		)
	)
	(wire
		(pts
			(xy 213.36 160.02) (xy 203.2 160.02)
		)
		(stroke
			(width 0)
			(type default)
		)
	)
	(bus
		(pts
			(xy 46.99 76.2) (xy 46.99 78.74)
		)
		(stroke
			(width 0)
			(type default)
		)
	)
	(bus
		(pts
			(xy 359.41 66.04) (xy 359.41 68.58)
		)
		(stroke
			(width 0)
			(type default)
		)
	)
	(wire
		(pts
			(xy 340.995 224.79) (xy 340.995 223.52)
		)
		(stroke
			(width 0)
			(type default)
		)
	)
	(wire
		(pts
			(xy 213.36 170.18) (xy 203.2 170.18)
		)
		(stroke
			(width 0)
			(type default)
		)
	)
	(bus
		(pts
			(xy 107.95 134.62) (xy 107.95 138.43)
		)
		(stroke
			(width 0)
			(type default)
		)
	)
	(bus
		(pts
			(xy 46.99 58.42) (xy 46.99 60.96)
		)
		(stroke
			(width 0)
			(type default)
		)
	)
	(bus
		(pts
			(xy 215.9 55.88) (xy 215.9 58.42)
		)
		(stroke
			(width 0)
			(type default)
		)
	)
	(wire
		(pts
			(xy 105.41 107.95) (xy 95.25 107.95)
		)
		(stroke
			(width 0)
			(type default)
		)
	)
	(bus
		(pts
			(xy 107.95 66.04) (xy 107.95 68.58)
		)
		(stroke
			(width 0)
			(type default)
		)
	)
	(bus
		(pts
			(xy 107.95 146.05) (xy 107.95 149.86)
		)
		(stroke
			(width 0)
			(type default)
		)
	)
	(wire
		(pts
			(xy 157.48 96.52) (xy 167.64 96.52)
		)
		(stroke
			(width 0)
			(type default)
		)
	)
	(wire
		(pts
			(xy 213.36 107.95) (xy 203.2 107.95)
		)
		(stroke
			(width 0)
			(type default)
		)
	)
	(wire
		(pts
			(xy 286.385 66.04) (xy 288.29 66.04)
		)
		(stroke
			(width 0)
			(type default)
		)
	)
	(wire
		(pts
			(xy 356.87 73.66) (xy 316.23 73.66)
		)
		(stroke
			(width 0)
			(type default)
		)
	)
	(wire
		(pts
			(xy 157.48 63.5) (xy 167.64 63.5)
		)
		(stroke
			(width 0)
			(type default)
		)
	)
	(wire
		(pts
			(xy 278.13 78.74) (xy 288.29 78.74)
		)
		(stroke
			(width 0)
			(type default)
		)
	)
	(wire
		(pts
			(xy 213.36 86.36) (xy 203.2 86.36)
		)
		(stroke
			(width 0)
			(type default)
		)
	)
	(wire
		(pts
			(xy 49.53 106.68) (xy 59.69 106.68)
		)
		(stroke
			(width 0)
			(type default)
		)
	)
	(wire
		(pts
			(xy 161.925 214.63) (xy 161.925 215.9)
		)
		(stroke
			(width 0)
			(type default)
		)
	)
	(polyline
		(pts
			(xy 318.77 102.87) (xy 318.77 114.935)
		)
		(stroke
			(width 0)
			(type default)
		)
	)
	(bus
		(pts
			(xy 215.9 44.45) (xy 215.9 46.99)
		)
		(stroke
			(width 0)
			(type default)
		)
	)
	(wire
		(pts
			(xy 49.53 86.36) (xy 59.69 86.36)
		)
		(stroke
			(width 0)
			(type default)
		)
	)
	(wire
		(pts
			(xy 266.065 116.205) (xy 266.065 123.825)
		)
		(stroke
			(width 0)
			(type default)
		)
	)
	(bus
		(pts
			(xy 107.95 77.47) (xy 107.95 80.01)
		)
		(stroke
			(width 0)
			(type default)
		)
	)
	(bus
		(pts
			(xy 154.94 58.42) (xy 154.94 60.96)
		)
		(stroke
			(width 0)
			(type default)
		)
	)
	(wire
		(pts
			(xy 213.36 74.93) (xy 203.2 74.93)
		)
		(stroke
			(width 0)
			(type default)
		)
	)
	(wire
		(pts
			(xy 326.39 77.47) (xy 316.23 77.47)
		)
		(stroke
			(width 0)
			(type default)
		)
	)
	(bus
		(pts
			(xy 215.9 157.48) (xy 215.9 160.02)
		)
		(stroke
			(width 0)
			(type default)
		)
	)
	(wire
		(pts
			(xy 105.41 88.9) (xy 95.25 88.9)
		)
		(stroke
			(width 0)
			(type default)
		)
	)
	(bus
		(pts
			(xy 154.94 73.66) (xy 154.94 76.2)
		)
		(stroke
			(width 0)
			(type default)
		)
	)
	(bus
		(pts
			(xy 107.95 99.06) (xy 107.95 101.6)
		)
		(stroke
			(width 0)
			(type default)
		)
	)
	(wire
		(pts
			(xy 213.36 167.64) (xy 203.2 167.64)
		)
		(stroke
			(width 0)
			(type default)
		)
	)
	(bus
		(pts
			(xy 46.99 66.04) (xy 46.99 68.58)
		)
		(stroke
			(width 0)
			(type default)
		)
	)
	(bus
		(pts
			(xy 107.95 53.34) (xy 107.95 55.88)
		)
		(stroke
			(width 0)
			(type default)
		)
	)
	(wire
		(pts
			(xy 49.53 53.34) (xy 59.69 53.34)
		)
		(stroke
			(width 0)
			(type default)
		)
	)
	(wire
		(pts
			(xy 213.36 88.9) (xy 203.2 88.9)
		)
		(stroke
			(width 0)
			(type default)
		)
	)
	(wire
		(pts
			(xy 49.53 83.82) (xy 59.69 83.82)
		)
		(stroke
			(width 0)
			(type default)
		)
	)
	(bus
		(pts
			(xy 215.9 50.8) (xy 215.9 53.34)
		)
		(stroke
			(width 0)
			(type default)
		)
	)
	(bus
		(pts
			(xy 215.9 88.9) (xy 215.9 91.44)
		)
		(stroke
			(width 0)
			(type default)
		)
	)
	(wire
		(pts
			(xy 280.67 123.825) (xy 283.845 123.825)
		)
		(stroke
			(width 0)
			(type default)
		)
	)
	(wire
		(pts
			(xy 59.69 114.3) (xy 49.53 114.3)
		)
		(stroke
			(width 0)
			(type default)
		)
	)
	(bus
		(pts
			(xy 46.99 73.66) (xy 46.99 76.2)
		)
		(stroke
			(width 0)
			(type default)
		)
	)
	(polyline
		(pts
			(xy 241.3 25.4) (xy 241.3 285.115)
		)
		(stroke
			(width 0)
			(type default)
		)
	)
	(wire
		(pts
			(xy 105.41 137.16) (xy 95.25 137.16)
		)
		(stroke
			(width 0)
			(type default)
		)
	)
	(wire
		(pts
			(xy 213.36 129.54) (xy 203.2 129.54)
		)
		(stroke
			(width 0)
			(type default)
		)
	)
	(wire
		(pts
			(xy 161.925 226.06) (xy 161.925 231.14)
		)
		(stroke
			(width 0)
			(type default)
		)
	)
	(wire
		(pts
			(xy 326.39 80.01) (xy 316.23 80.01)
		)
		(stroke
			(width 0)
			(type default)
		)
	)
	(bus
		(pts
			(xy 107.95 167.64) (xy 107.95 171.45)
		)
		(stroke
			(width 0)
			(type default)
		)
	)
	(polyline
		(pts
			(xy 285.75 106.045) (xy 330.2 106.045)
		)
		(stroke
			(width 0)
			(type default)
		)
	)
	(wire
		(pts
			(xy 86.36 207.01) (xy 86.36 212.09)
		)
		(stroke
			(width 0)
			(type default)
		)
	)
	(bus
		(pts
			(xy 215.9 72.39) (xy 215.9 77.47)
		)
		(stroke
			(width 0)
			(type default)
		)
	)
	(wire
		(pts
			(xy 105.41 80.01) (xy 95.25 80.01)
		)
		(stroke
			(width 0)
			(type default)
		)
	)
	(bus
		(pts
			(xy 215.9 68.58) (xy 215.9 72.39)
		)
		(stroke
			(width 0)
			(type default)
		)
	)
	(wire
		(pts
			(xy 49.53 78.74) (xy 59.69 78.74)
		)
		(stroke
			(width 0)
			(type default)
		)
	)
	(wire
		(pts
			(xy 353.695 126.365) (xy 367.665 126.365)
		)
		(stroke
			(width 0)
			(type default)
		)
	)
	(bus
		(pts
			(xy 108.585 42.545) (xy 107.95 43.18)
		)
		(stroke
			(width 0)
			(type default)
		)
	)
	(bus
		(pts
			(xy 107.95 96.52) (xy 107.95 99.06)
		)
		(stroke
			(width 0)
			(type default)
		)
	)
	(wire
		(pts
			(xy 105.41 113.03) (xy 95.25 113.03)
		)
		(stroke
			(width 0)
			(type default)
		)
	)
	(wire
		(pts
			(xy 283.845 120.65) (xy 280.67 120.65)
		)
		(stroke
			(width 0)
			(type default)
		)
	)
	(bus
		(pts
			(xy 107.95 68.58) (xy 107.95 72.39)
		)
		(stroke
			(width 0)
			(type default)
		)
	)
	(wire
		(pts
			(xy 157.48 53.34) (xy 167.64 53.34)
		)
		(stroke
			(width 0)
			(type default)
		)
	)
	(wire
		(pts
			(xy 361.95 217.17) (xy 361.95 218.44)
		)
		(stroke
			(width 0)
			(type default)
		)
	)
	(bus
		(pts
			(xy 107.95 105.41) (xy 107.95 110.49)
		)
		(stroke
			(width 0)
			(type default)
		)
	)
	(wire
		(pts
			(xy 49.53 76.2) (xy 59.69 76.2)
		)
		(stroke
			(width 0)
			(type default)
		)
	)
	(bus
		(pts
			(xy 215.9 132.08) (xy 215.9 134.62)
		)
		(stroke
			(width 0)
			(type default)
		)
	)
	(wire
		(pts
			(xy 86.36 241.3) (xy 86.36 251.46)
		)
		(stroke
			(width 0)
			(type default)
		)
	)
	(wire
		(pts
			(xy 105.41 160.02) (xy 95.25 160.02)
		)
		(stroke
			(width 0)
			(type default)
		)
	)
	(bus
		(pts
			(xy 215.9 83.82) (xy 215.9 86.36)
		)
		(stroke
			(width 0)
			(type default)
		)
	)
	(wire
		(pts
			(xy 326.39 82.55) (xy 316.23 82.55)
		)
		(stroke
			(width 0)
			(type default)
		)
	)
	(wire
		(pts
			(xy 59.69 121.92) (xy 49.53 121.92)
		)
		(stroke
			(width 0)
			(type default)
		)
	)
	(wire
		(pts
			(xy 157.48 55.88) (xy 167.64 55.88)
		)
		(stroke
			(width 0)
			(type default)
		)
	)
	(wire
		(pts
			(xy 105.41 157.48) (xy 95.25 157.48)
		)
		(stroke
			(width 0)
			(type default)
		)
	)
	(polyline
		(pts
			(xy 12.065 184.15) (xy 407.67 184.15)
		)
		(stroke
			(width 0)
			(type default)
		)
	)
	(wire
		(pts
			(xy 364.49 117.475) (xy 367.665 117.475)
		)
		(stroke
			(width 0)
			(type default)
		)
	)
	(wire
		(pts
			(xy 278.13 60.325) (xy 278.13 59.69)
		)
		(stroke
			(width 0)
			(type default)
		)
	)
	(polyline
		(pts
			(xy 285.115 112.395) (xy 330.2 112.395)
		)
		(stroke
			(width 0)
			(type default)
		)
	)
	(bus
		(pts
			(xy 215.9 105.41) (xy 215.9 110.49)
		)
		(stroke
			(width 0)
			(type default)
		)
	)
	(wire
		(pts
			(xy 359.41 121.92) (xy 359.41 131.445)
		)
		(stroke
			(width 0)
			(type default)
		)
	)
	(wire
		(pts
			(xy 213.36 53.34) (xy 203.2 53.34)
		)
		(stroke
			(width 0)
			(type default)
		)
	)
	(wire
		(pts
			(xy 105.41 134.62) (xy 95.25 134.62)
		)
		(stroke
			(width 0)
			(type default)
		)
	)
	(bus
		(pts
			(xy 154.94 66.04) (xy 154.94 68.58)
		)
		(stroke
			(width 0)
			(type default)
		)
	)
	(bus
		(pts
			(xy 154.94 106.68) (xy 154.94 111.76)
		)
		(stroke
			(width 0)
			(type default)
		)
	)
	(wire
		(pts
			(xy 104.14 203.2) (xy 104.14 212.09)
		)
		(stroke
			(width 0)
			(type default)
		)
	)
	(wire
		(pts
			(xy 266.065 123.825) (xy 266.065 129.54)
		)
		(stroke
			(width 0)
			(type default)
		)
	)
	(wire
		(pts
			(xy 105.41 58.42) (xy 95.25 58.42)
		)
		(stroke
			(width 0)
			(type default)
		)
	)
	(bus
		(pts
			(xy 361.95 61.595) (xy 360.045 61.595)
		)
		(stroke
			(width 0)
			(type default)
		)
	)
	(wire
		(pts
			(xy 49.53 68.58) (xy 59.69 68.58)
		)
		(stroke
			(width 0)
			(type default)
		)
	)
	(wire
		(pts
			(xy 67.31 212.09) (xy 67.31 210.82)
		)
		(stroke
			(width 0)
			(type default)
		)
	)
	(wire
		(pts
			(xy 105.41 140.97) (xy 95.25 140.97)
		)
		(stroke
			(width 0)
			(type default)
		)
	)
	(wire
		(pts
			(xy 278.13 69.85) (xy 288.29 69.85)
		)
		(stroke
			(width 0)
			(type default)
		)
	)
	(bus
		(pts
			(xy 215.9 138.43) (xy 215.9 143.51)
		)
		(stroke
			(width 0)
			(type default)
		)
	)
	(bus
		(pts
			(xy 154.94 93.98) (xy 154.94 96.52)
		)
		(stroke
			(width 0)
			(type default)
		)
	)
	(bus
		(pts
			(xy 154.94 71.12) (xy 154.94 73.66)
		)
		(stroke
			(width 0)
			(type default)
		)
	)
	(bus
		(pts
			(xy 154.94 68.58) (xy 154.94 71.12)
		)
		(stroke
			(width 0)
			(type default)
		)
	)
	(wire
		(pts
			(xy 213.36 152.4) (xy 203.2 152.4)
		)
		(stroke
			(width 0)
			(type default)
		)
	)
	(bus
		(pts
			(xy 107.95 88.9) (xy 107.95 91.44)
		)
		(stroke
			(width 0)
			(type default)
		)
	)
	(bus
		(pts
			(xy 107.95 132.08) (xy 107.95 134.62)
		)
		(stroke
			(width 0)
			(type default)
		)
	)
	(bus
		(pts
			(xy 359.41 62.23) (xy 359.41 63.5)
		)
		(stroke
			(width 0)
			(type default)
		)
	)
	(wire
		(pts
			(xy 340.995 217.17) (xy 340.995 218.44)
		)
		(stroke
			(width 0)
			(type default)
		)
	)
	(bus
		(pts
			(xy 44.45 42.545) (xy 46.355 42.545)
		)
		(stroke
			(width 0)
			(type default)
		)
	)
	(wire
		(pts
			(xy 105.41 124.46) (xy 95.25 124.46)
		)
		(stroke
			(width 0)
			(type default)
		)
	)
	(wire
		(pts
			(xy 372.745 121.92) (xy 379.73 121.92)
		)
		(stroke
			(width 0)
			(type default)
		)
	)
	(bus
		(pts
			(xy 215.9 146.05) (xy 215.9 149.86)
		)
		(stroke
			(width 0)
			(type default)
		)
	)
	(bus
		(pts
			(xy 46.99 86.36) (xy 46.99 88.9)
		)
		(stroke
			(width 0)
			(type default)
		)
	)
	(wire
		(pts
			(xy 49.53 91.44) (xy 59.69 91.44)
		)
		(stroke
			(width 0)
			(type default)
		)
	)
	(bus
		(pts
			(xy 154.94 96.52) (xy 154.94 104.14)
		)
		(stroke
			(width 0)
			(type default)
		)
	)
	(wire
		(pts
			(xy 105.41 53.34) (xy 95.25 53.34)
		)
		(stroke
			(width 0)
			(type default)
		)
	)
	(bus
		(pts
			(xy 107.95 127) (xy 107.95 129.54)
		)
		(stroke
			(width 0)
			(type default)
		)
	)
	(bus
		(pts
			(xy 215.9 134.62) (xy 215.9 138.43)
		)
		(stroke
			(width 0)
			(type default)
		)
	)
	(wire
		(pts
			(xy 105.41 96.52) (xy 95.25 96.52)
		)
		(stroke
			(width 0)
			(type default)
		)
	)
	(bus
		(pts
			(xy 107.95 162.56) (xy 107.95 165.1)
		)
		(stroke
			(width 0)
			(type default)
		)
	)
	(wire
		(pts
			(xy 105.41 46.99) (xy 95.25 46.99)
		)
		(stroke
			(width 0)
			(type default)
		)
	)
	(bus
		(pts
			(xy 152.4 42.545) (xy 154.305 42.545)
		)
		(stroke
			(width 0)
			(type default)
		)
	)
	(wire
		(pts
			(xy 164.465 214.63) (xy 164.465 215.9)
		)
		(stroke
			(width 0)
			(type default)
		)
	)
	(bus
		(pts
			(xy 331.47 75.565) (xy 329.565 75.565)
		)
		(stroke
			(width 0)
			(type default)
		)
	)
	(wire
		(pts
			(xy 213.36 63.5) (xy 203.2 63.5)
		)
		(stroke
			(width 0)
			(type default)
		)
	)
	(bus
		(pts
			(xy 107.95 119.38) (xy 107.95 121.92)
		)
		(stroke
			(width 0)
			(type default)
		)
	)
	(bus
		(pts
			(xy 46.99 116.84) (xy 46.99 119.38)
		)
		(stroke
			(width 0)
			(type default)
		)
	)
	(wire
		(pts
			(xy 213.36 173.99) (xy 203.2 173.99)
		)
		(stroke
			(width 0)
			(type default)
		)
	)
	(bus
		(pts
			(xy 154.94 116.84) (xy 154.94 119.38)
		)
		(stroke
			(width 0)
			(type default)
		)
	)
	(wire
		(pts
			(xy 286.385 52.705) (xy 278.13 52.705)
		)
		(stroke
			(width 0)
			(type default)
		)
	)
	(bus
		(pts
			(xy 107.95 58.42) (xy 107.95 60.96)
		)
		(stroke
			(width 0)
			(type default)
		)
	)
	(wire
		(pts
			(xy 284.48 85.09) (xy 284.48 87.63)
		)
		(stroke
			(width 0)
			(type default)
		)
	)
	(wire
		(pts
			(xy 161.925 231.14) (xy 164.465 231.14)
		)
		(stroke
			(width 0)
			(type default)
		)
	)
	(wire
		(pts
			(xy 172.72 225.425) (xy 172.72 231.14)
		)
		(stroke
			(width 0)
			(type default)
		)
	)
	(wire
		(pts
			(xy 213.36 66.04) (xy 203.2 66.04)
		)
		(stroke
			(width 0)
			(type default)
		)
	)
	(wire
		(pts
			(xy 105.41 104.14) (xy 95.25 104.14)
		)
		(stroke
			(width 0)
			(type default)
		)
	)
	(bus
		(pts
			(xy 107.95 60.96) (xy 107.95 63.5)
		)
		(stroke
			(width 0)
			(type default)
		)
	)
	(wire
		(pts
			(xy 267.97 60.325) (xy 267.97 59.69)
		)
		(stroke
			(width 0)
			(type default)
		)
	)
	(bus
		(pts
			(xy 107.95 138.43) (xy 107.95 143.51)
		)
		(stroke
			(width 0)
			(type default)
		)
	)
	(bus
		(pts
			(xy 46.99 60.96) (xy 46.99 66.04)
		)
		(stroke
			(width 0)
			(type default)
		)
	)
	(polyline
		(pts
			(xy 133.35 25.4) (xy 133.35 285.115)
		)
		(stroke
			(width 0)
			(type default)
		)
	)
	(bus
		(pts
			(xy 154.94 83.82) (xy 154.94 86.36)
		)
		(stroke
			(width 0)
			(type default)
		)
	)
	(bus
		(pts
			(xy 46.99 44.45) (xy 46.99 46.99)
		)
		(stroke
			(width 0)
			(type default)
		)
	)
	(bus
		(pts
			(xy 328.93 76.2) (xy 328.93 77.47)
		)
		(stroke
			(width 0)
			(type default)
		)
	)
	(wire
		(pts
			(xy 213.36 101.6) (xy 203.2 101.6)
		)
		(stroke
			(width 0)
			(type default)
		)
	)
	(wire
		(pts
			(xy 157.48 83.82) (xy 167.64 83.82)
		)
		(stroke
			(width 0)
			(type default)
		)
	)
	(wire
		(pts
			(xy 157.48 88.9) (xy 167.64 88.9)
		)
		(stroke
			(width 0)
			(type default)
		)
	)
	(wire
		(pts
			(xy 105.41 55.88) (xy 95.25 55.88)
		)
		(stroke
			(width 0)
			(type default)
		)
	)
	(bus
		(pts
			(xy 107.95 121.92) (xy 107.95 124.46)
		)
		(stroke
			(width 0)
			(type default)
		)
	)
	(wire
		(pts
			(xy 164.465 204.47) (xy 164.465 207.01)
		)
		(stroke
			(width 0)
			(type default)
		)
	)
	(polyline
		(pts
			(xy 285.115 109.22) (xy 330.2 109.22)
		)
		(stroke
			(width 0)
			(type default)
		)
	)
	(bus
		(pts
			(xy 154.94 88.9) (xy 154.94 91.44)
		)
		(stroke
			(width 0)
			(type default)
		)
	)
	(wire
		(pts
			(xy 49.53 60.96) (xy 59.69 60.96)
		)
		(stroke
			(width 0)
			(type default)
		)
	)
	(bus
		(pts
			(xy 215.9 60.96) (xy 215.9 63.5)
		)
		(stroke
			(width 0)
			(type default)
		)
	)
	(wire
		(pts
			(xy 105.41 146.05) (xy 95.25 146.05)
		)
		(stroke
			(width 0)
			(type default)
		)
	)
	(wire
		(pts
			(xy 167.64 114.3) (xy 157.48 114.3)
		)
		(stroke
			(width 0)
			(type default)
		)
	)
	(bus
		(pts
			(xy 107.95 46.99) (xy 107.95 50.8)
		)
		(stroke
			(width 0)
			(type default)
		)
	)
	(wire
		(pts
			(xy 271.78 116.205) (xy 271.78 120.65)
		)
		(stroke
			(width 0)
			(type default)
		)
	)
	(wire
		(pts
			(xy 203.2 49.53) (xy 213.36 49.53)
		)
		(stroke
			(width 0)
			(type default)
		)
	)
	(bus
		(pts
			(xy 215.9 58.42) (xy 215.9 60.96)
		)
		(stroke
			(width 0)
			(type default)
		)
	)
	(wire
		(pts
			(xy 278.13 81.28) (xy 288.29 81.28)
		)
		(stroke
			(width 0)
			(type default)
		)
	)
	(bus
		(pts
			(xy 107.95 86.36) (xy 107.95 88.9)
		)
		(stroke
			(width 0)
			(type default)
		)
	)
	(wire
		(pts
			(xy 213.36 132.08) (xy 203.2 132.08)
		)
		(stroke
			(width 0)
			(type default)
		)
	)
	(bus
		(pts
			(xy 215.9 154.94) (xy 215.9 157.48)
		)
		(stroke
			(width 0)
			(type default)
		)
	)
	(wire
		(pts
			(xy 60.96 203.2) (xy 104.14 203.2)
		)
		(stroke
			(width 0)
			(type default)
		)
	)
	(bus
		(pts
			(xy 154.94 53.34) (xy 154.94 58.42)
		)
		(stroke
			(width 0)
			(type default)
		)
	)
	(wire
		(pts
			(xy 49.53 88.9) (xy 59.69 88.9)
		)
		(stroke
			(width 0)
			(type default)
		)
	)
	(wire
		(pts
			(xy 344.805 117.475) (xy 364.49 117.475)
		)
		(stroke
			(width 0)
			(type default)
		)
	)
	(wire
		(pts
			(xy 351.155 217.17) (xy 351.155 218.44)
		)
		(stroke
			(width 0)
			(type default)
		)
	)
	(bus
		(pts
			(xy 215.9 110.49) (xy 215.9 113.03)
		)
		(stroke
			(width 0)
			(type default)
		)
	)
	(wire
		(pts
			(xy 164.465 226.06) (xy 164.465 231.14)
		)
		(stroke
			(width 0)
			(type default)
		)
	)
	(bus
		(pts
			(xy 46.99 81.28) (xy 46.99 83.82)
		)
		(stroke
			(width 0)
			(type default)
		)
	)
	(bus
		(pts
			(xy 107.95 165.1) (xy 107.95 167.64)
		)
		(stroke
			(width 0)
			(type default)
		)
	)
	(wire
		(pts
			(xy 157.48 60.96) (xy 167.64 60.96)
		)
		(stroke
			(width 0)
			(type default)
		)
	)
	(wire
		(pts
			(xy 213.36 157.48) (xy 203.2 157.48)
		)
		(stroke
			(width 0)
			(type default)
		)
	)
	(wire
		(pts
			(xy 213.36 134.62) (xy 203.2 134.62)
		)
		(stroke
			(width 0)
			(type default)
		)
	)
	(bus
		(pts
			(xy 215.9 143.51) (xy 215.9 146.05)
		)
		(stroke
			(width 0)
			(type default)
		)
	)
	(wire
		(pts
			(xy 213.36 58.42) (xy 203.2 58.42)
		)
		(stroke
			(width 0)
			(type default)
		)
	)
	(bus
		(pts
			(xy 46.99 93.98) (xy 46.99 96.52)
		)
		(stroke
			(width 0)
			(type default)
		)
	)
	(wire
		(pts
			(xy 213.36 154.94) (xy 203.2 154.94)
		)
		(stroke
			(width 0)
			(type default)
		)
	)
	(bus
		(pts
			(xy 154.94 104.14) (xy 154.94 106.68)
		)
		(stroke
			(width 0)
			(type default)
		)
	)
	(wire
		(pts
			(xy 157.48 71.12) (xy 167.64 71.12)
		)
		(stroke
			(width 0)
			(type default)
		)
	)
	(bus
		(pts
			(xy 215.9 165.1) (xy 215.9 167.64)
		)
		(stroke
			(width 0)
			(type default)
		)
	)
	(wire
		(pts
			(xy 213.36 80.01) (xy 203.2 80.01)
		)
		(stroke
			(width 0)
			(type default)
		)
	)
	(bus
		(pts
			(xy 107.95 124.46) (xy 107.95 127)
		)
		(stroke
			(width 0)
			(type default)
		)
	)
	(wire
		(pts
			(xy 49.53 55.88) (xy 59.69 55.88)
		)
		(stroke
			(width 0)
			(type default)
		)
	)
	(wire
		(pts
			(xy 356.87 71.12) (xy 334.01 71.12)
		)
		(stroke
			(width 0)
			(type default)
		)
	)
	(wire
		(pts
			(xy 167.64 121.92) (xy 157.48 121.92)
		)
		(stroke
			(width 0)
			(type default)
		)
	)
	(wire
		(pts
			(xy 266.065 134.62) (xy 266.065 136.525)
		)
		(stroke
			(width 0)
			(type default)
		)
	)
	(wire
		(pts
			(xy 49.53 99.06) (xy 59.69 99.06)
		)
		(stroke
			(width 0)
			(type default)
		)
	)
	(bus
		(pts
			(xy 154.305 42.545) (xy 154.94 43.18)
		)
		(stroke
			(width 0)
			(type default)
		)
	)
	(wire
		(pts
			(xy 86.36 217.17) (xy 86.36 228.6)
		)
		(stroke
			(width 0)
			(type default)
		)
	)
	(bus
		(pts
			(xy 107.95 110.49) (xy 107.95 113.03)
		)
		(stroke
			(width 0)
			(type default)
		)
	)
	(bus
		(pts
			(xy 46.99 88.9) (xy 46.99 91.44)
		)
		(stroke
			(width 0)
			(type default)
		)
	)
	(wire
		(pts
			(xy 105.41 132.08) (xy 95.25 132.08)
		)
		(stroke
			(width 0)
			(type default)
		)
	)
	(bus
		(pts
			(xy 215.9 162.56) (xy 215.9 165.1)
		)
		(stroke
			(width 0)
			(type default)
		)
	)
	(bus
		(pts
			(xy 46.99 53.34) (xy 46.99 58.42)
		)
		(stroke
			(width 0)
			(type default)
		)
	)
	(wire
		(pts
			(xy 213.36 165.1) (xy 203.2 165.1)
		)
		(stroke
			(width 0)
			(type default)
		)
	)
	(wire
		(pts
			(xy 278.13 74.93) (xy 288.29 74.93)
		)
		(stroke
			(width 0)
			(type default)
		)
	)
	(bus
		(pts
			(xy 154.94 43.18) (xy 154.94 44.45)
		)
		(stroke
			(width 0)
			(type default)
		)
	)
	(wire
		(pts
			(xy 203.2 82.55) (xy 213.36 82.55)
		)
		(stroke
			(width 0)
			(type default)
		)
	)
	(bus
		(pts
			(xy 154.94 50.8) (xy 154.94 53.34)
		)
		(stroke
			(width 0)
			(type default)
		)
	)
	(bus
		(pts
			(xy 154.94 91.44) (xy 154.94 93.98)
		)
		(stroke
			(width 0)
			(type default)
		)
	)
	(wire
		(pts
			(xy 105.41 154.94) (xy 95.25 154.94)
		)
		(stroke
			(width 0)
			(type default)
		)
	)
	(wire
		(pts
			(xy 359.41 121.92) (xy 367.665 121.92)
		)
		(stroke
			(width 0)
			(type default)
		)
	)
	(wire
		(pts
			(xy 284.48 87.63) (xy 288.29 87.63)
		)
		(stroke
			(width 0)
			(type default)
		)
	)
	(bus
		(pts
			(xy 360.045 61.595) (xy 359.41 62.23)
		)
		(stroke
			(width 0)
			(type default)
		)
	)
	(wire
		(pts
			(xy 157.48 86.36) (xy 167.64 86.36)
		)
		(stroke
			(width 0)
			(type default)
		)
	)
	(bus
		(pts
			(xy 154.94 111.76) (xy 154.94 114.3)
		)
		(stroke
			(width 0)
			(type default)
		)
	)
	(bus
		(pts
			(xy 215.9 63.5) (xy 215.9 66.04)
		)
		(stroke
			(width 0)
			(type default)
		)
	)
	(wire
		(pts
			(xy 364.49 136.525) (xy 364.49 138.43)
		)
		(stroke
			(width 0)
			(type default)
		)
	)
	(wire
		(pts
			(xy 105.41 66.04) (xy 95.25 66.04)
		)
		(stroke
			(width 0)
			(type default)
		)
	)
	(bus
		(pts
			(xy 215.9 53.34) (xy 215.9 55.88)
		)
		(stroke
			(width 0)
			(type default)
		)
	)
	(wire
		(pts
			(xy 213.36 124.46) (xy 203.2 124.46)
		)
		(stroke
			(width 0)
			(type default)
		)
	)
	(wire
		(pts
			(xy 278.13 72.39) (xy 288.29 72.39)
		)
		(stroke
			(width 0)
			(type default)
		)
	)
	(wire
		(pts
			(xy 266.065 220.98) (xy 269.875 220.98)
		)
		(stroke
			(width 0)
			(type default)
		)
	)
	(bus
		(pts
			(xy 46.99 83.82) (xy 46.99 86.36)
		)
		(stroke
			(width 0)
			(type default)
		)
	)
	(wire
		(pts
			(xy 213.36 55.88) (xy 203.2 55.88)
		)
		(stroke
			(width 0)
			(type default)
		)
	)
	(bus
		(pts
			(xy 154.94 76.2) (xy 154.94 78.74)
		)
		(stroke
			(width 0)
			(type default)
		)
	)
	(bus
		(pts
			(xy 154.94 44.45) (xy 154.94 46.99)
		)
		(stroke
			(width 0)
			(type default)
		)
	)
	(bus
		(pts
			(xy 154.94 114.3) (xy 154.94 116.84)
		)
		(stroke
			(width 0)
			(type default)
		)
	)
	(wire
		(pts
			(xy 213.36 46.99) (xy 203.2 46.99)
		)
		(stroke
			(width 0)
			(type default)
		)
	)
	(wire
		(pts
			(xy 58.42 247.65) (xy 59.69 247.65)
		)
		(stroke
			(width 0)
			(type default)
		)
	)
	(wire
		(pts
			(xy 95.25 115.57) (xy 105.41 115.57)
		)
		(stroke
			(width 0)
			(type default)
		)
	)
	(wire
		(pts
			(xy 49.53 73.66) (xy 59.69 73.66)
		)
		(stroke
			(width 0)
			(type default)
		)
	)
	(bus
		(pts
			(xy 107.95 72.39) (xy 107.95 77.47)
		)
		(stroke
			(width 0)
			(type default)
		)
	)
	(bus
		(pts
			(xy 107.95 63.5) (xy 107.95 66.04)
		)
		(stroke
			(width 0)
			(type default)
		)
	)
	(bus
		(pts
			(xy 107.95 83.82) (xy 107.95 86.36)
		)
		(stroke
			(width 0)
			(type default)
		)
	)
	(wire
		(pts
			(xy 105.41 101.6) (xy 95.25 101.6)
		)
		(stroke
			(width 0)
			(type default)
		)
	)
	(wire
		(pts
			(xy 157.48 76.2) (xy 167.64 76.2)
		)
		(stroke
			(width 0)
			(type default)
		)
	)
	(bus
		(pts
			(xy 107.95 44.45) (xy 107.95 46.99)
		)
		(stroke
			(width 0)
			(type default)
		)
	)
	(bus
		(pts
			(xy 328.93 77.47) (xy 328.93 80.01)
		)
		(stroke
			(width 0)
			(type default)
		)
	)
	(bus
		(pts
			(xy 46.99 71.12) (xy 46.99 73.66)
		)
		(stroke
			(width 0)
			(type default)
		)
	)
	(bus
		(pts
			(xy 215.9 119.38) (xy 215.9 121.92)
		)
		(stroke
			(width 0)
			(type default)
		)
	)
	(wire
		(pts
			(xy 157.48 91.44) (xy 167.64 91.44)
		)
		(stroke
			(width 0)
			(type default)
		)
	)
	(bus
		(pts
			(xy 46.99 106.68) (xy 46.99 111.76)
		)
		(stroke
			(width 0)
			(type default)
		)
	)
	(wire
		(pts
			(xy 36.83 205.74) (xy 36.83 207.01)
		)
		(stroke
			(width 0)
			(type default)
		)
	)
	(wire
		(pts
			(xy 49.53 93.98) (xy 59.69 93.98)
		)
		(stroke
			(width 0)
			(type default)
		)
	)
	(wire
		(pts
			(xy 213.36 140.97) (xy 203.2 140.97)
		)
		(stroke
			(width 0)
			(type default)
		)
	)
	(wire
		(pts
			(xy 95.25 82.55) (xy 105.41 82.55)
		)
		(stroke
			(width 0)
			(type default)
		)
	)
	(bus
		(pts
			(xy 215.9 149.86) (xy 215.9 152.4)
		)
		(stroke
			(width 0)
			(type default)
		)
	)
	(bus
		(pts
			(xy 329.565 75.565) (xy 328.93 76.2)
		)
		(stroke
			(width 0)
			(type default)
		)
	)
	(wire
		(pts
			(xy 58.42 237.49) (xy 78.74 237.49)
		)
		(stroke
			(width 0)
			(type default)
		)
	)
	(bus
		(pts
			(xy 215.9 152.4) (xy 215.9 154.94)
		)
		(stroke
			(width 0)
			(type default)
		)
	)
	(bus
		(pts
			(xy 215.9 43.18) (xy 215.9 44.45)
		)
		(stroke
			(width 0)
			(type default)
		)
	)
	(wire
		(pts
			(xy 164.465 212.09) (xy 164.465 214.63)
		)
		(stroke
			(width 0)
			(type default)
		)
	)
	(wire
		(pts
			(xy 213.36 127) (xy 203.2 127)
		)
		(stroke
			(width 0)
			(type default)
		)
	)
	(bus
		(pts
			(xy 46.99 111.76) (xy 46.99 114.3)
		)
		(stroke
			(width 0)
			(type default)
		)
	)
	(bus
		(pts
			(xy 46.99 91.44) (xy 46.99 93.98)
		)
		(stroke
			(width 0)
			(type default)
		)
	)
	(wire
		(pts
			(xy 157.48 49.53) (xy 167.64 49.53)
		)
		(stroke
			(width 0)
			(type default)
		)
	)
	(bus
		(pts
			(xy 46.99 78.74) (xy 46.99 81.28)
		)
		(stroke
			(width 0)
			(type default)
		)
	)
	(wire
		(pts
			(xy 359.41 136.525) (xy 359.41 138.43)
		)
		(stroke
			(width 0)
			(type default)
		)
	)
	(wire
		(pts
			(xy 157.48 46.99) (xy 167.64 46.99)
		)
		(stroke
			(width 0)
			(type default)
		)
	)
	(bus
		(pts
			(xy 107.95 55.88) (xy 107.95 58.42)
		)
		(stroke
			(width 0)
			(type default)
		)
	)
	(bus
		(pts
			(xy 215.9 96.52) (xy 215.9 99.06)
		)
		(stroke
			(width 0)
			(type default)
		)
	)
	(label "A.DQ10"
		(at 105.41 91.44 180)
		(effects
			(font
				(size 1.27 1.27)
			)
			(justify right bottom)
		)
	)
	(label "A.DQ31"
		(at 105.41 170.18 180)
		(effects
			(font
				(size 1.27 1.27)
			)
			(justify right bottom)
		)
	)
	(label "B.CK1_N"
		(at 157.627 63.5 0)
		(effects
			(font
				(size 1.27 1.27)
			)
			(justify left bottom)
		)
	)
	(label "A.CB1"
		(at 49.53 116.84 0)
		(effects
			(font
				(size 1.27 1.27)
			)
			(justify left bottom)
		)
	)
	(label "B.CA9"
		(at 157.48 91.44 0)
		(effects
			(font
				(size 1.27 1.27)
			)
			(justify left bottom)
		)
	)
	(label "B.DQ12"
		(at 213.36 96.52 180)
		(effects
			(font
				(size 1.27 1.27)
			)
			(justify right bottom)
		)
	)
	(label "A.DQ29"
		(at 105.41 165.1 180)
		(effects
			(font
				(size 1.27 1.27)
			)
			(justify right bottom)
		)
	)
	(label "B.DQ10"
		(at 213.36 91.44 180)
		(effects
			(font
				(size 1.27 1.27)
			)
			(justify right bottom)
		)
	)
	(label "A.DQS1_N"
		(at 105.41 82.55 180)
		(effects
			(font
				(size 1.27 1.27)
			)
			(justify right bottom)
		)
	)
	(label "A.~{CS1}"
		(at 49.53 49.53 0)
		(effects
			(font
				(size 1.27 1.27)
			)
			(justify left bottom)
		)
	)
	(label "A.DQ13"
		(at 105.41 99.06 180)
		(effects
			(font
				(size 1.27 1.27)
			)
			(justify right bottom)
		)
	)
	(label "A.DQS2_N"
		(at 105.41 115.57 180)
		(effects
			(font
				(size 1.27 1.27)
			)
			(justify right bottom)
		)
	)
	(label "B.~{DM1}"
		(at 213.36 107.95 180)
		(effects
			(font
				(size 1.27 1.27)
			)
			(justify right bottom)
		)
	)
	(label "A.CA8"
		(at 49.53 88.9 0)
		(effects
			(font
				(size 1.27 1.27)
			)
			(justify left bottom)
		)
	)
	(label "A.CA12"
		(at 49.53 99.06 0)
		(effects
			(font
				(size 1.27 1.27)
			)
			(justify left bottom)
		)
	)
	(label "A.DQ23"
		(at 105.41 137.16 180)
		(effects
			(font
				(size 1.27 1.27)
			)
			(justify right bottom)
		)
	)
	(label "B.DQS3_N"
		(at 213.36 148.59 180)
		(effects
			(font
				(size 1.27 1.27)
			)
			(justify right bottom)
		)
	)
	(label "B.DQ7"
		(at 213.36 71.12 180)
		(effects
			(font
				(size 1.27 1.27)
			)
			(justify right bottom)
		)
	)
	(label "VSS_DET1"
		(at 254 120.65 0)
		(effects
			(font
				(size 1.27 1.27)
			)
			(justify left bottom)
		)
	)
	(label "A.CA6"
		(at 49.53 83.82 0)
		(effects
			(font
				(size 1.27 1.27)
			)
			(justify left bottom)
		)
	)
	(label "B.CB2"
		(at 157.48 119.38 0)
		(effects
			(font
				(size 1.27 1.27)
			)
			(justify left bottom)
		)
	)
	(label "B.CA7"
		(at 157.48 86.36 0)
		(effects
			(font
				(size 1.27 1.27)
			)
			(justify left bottom)
		)
	)
	(label "A.DQ12"
		(at 105.41 96.52 180)
		(effects
			(font
				(size 1.27 1.27)
			)
			(justify right bottom)
		)
	)
	(label "A.CA9"
		(at 49.53 91.44 0)
		(effects
			(font
				(size 1.27 1.27)
			)
			(justify left bottom)
		)
	)
	(label "A.~{DM1}"
		(at 105.41 107.95 180)
		(effects
			(font
				(size 1.27 1.27)
			)
			(justify right bottom)
		)
	)
	(label "B.DQ6"
		(at 213.36 68.58 180)
		(effects
			(font
				(size 1.27 1.27)
			)
			(justify right bottom)
		)
	)
	(label "RFU1"
		(at 344.805 117.475 0)
		(effects
			(font
				(size 1.27 1.27)
			)
			(justify left bottom)
		)
	)
	(label "A.CK0_N"
		(at 49.53 55.88 0)
		(effects
			(font
				(size 1.27 1.27)
			)
			(justify left bottom)
		)
	)
	(label "B.DQ26"
		(at 213.36 157.48 180)
		(effects
			(font
				(size 1.27 1.27)
			)
			(justify right bottom)
		)
	)
	(label "A.~{DM0}"
		(at 105.41 74.93 180)
		(effects
			(font
				(size 1.27 1.27)
			)
			(justify right bottom)
		)
	)
	(label "A.DQ15"
		(at 105.41 104.14 180)
		(effects
			(font
				(size 1.27 1.27)
			)
			(justify right bottom)
		)
	)
	(label "A.DQ5"
		(at 105.41 66.04 180)
		(effects
			(font
				(size 1.27 1.27)
			)
			(justify right bottom)
		)
	)
	(label "B.DQ27"
		(at 213.36 160.02 180)
		(effects
			(font
				(size 1.27 1.27)
			)
			(justify right bottom)
		)
	)
	(label "A.CK1_N"
		(at 49.677 63.5 0)
		(effects
			(font
				(size 1.27 1.27)
			)
			(justify left bottom)
		)
	)
	(label "B.DQ29"
		(at 213.36 165.1 180)
		(effects
			(font
				(size 1.27 1.27)
			)
			(justify right bottom)
		)
	)
	(label "B.CK1_P"
		(at 157.48 60.96 0)
		(effects
			(font
				(size 1.27 1.27)
			)
			(justify left bottom)
		)
	)
	(label "B.DQ24"
		(at 213.36 152.4 180)
		(effects
			(font
				(size 1.27 1.27)
			)
			(justify right bottom)
		)
	)
	(label "B.CA10"
		(at 157.48 93.98 0)
		(effects
			(font
				(size 1.27 1.27)
			)
			(justify left bottom)
		)
	)
	(label "A.DQS3_P"
		(at 105.41 146.05 180)
		(effects
			(font
				(size 1.27 1.27)
			)
			(justify right bottom)
		)
	)
	(label "A.CK1_P"
		(at 49.53 60.96 0)
		(effects
			(font
				(size 1.27 1.27)
			)
			(justify left bottom)
		)
	)
	(label "A.CK0_P"
		(at 49.53 53.34 0)
		(effects
			(font
				(size 1.27 1.27)
			)
			(justify left bottom)
		)
	)
	(label "B.CA6"
		(at 157.48 83.82 0)
		(effects
			(font
				(size 1.27 1.27)
			)
			(justify left bottom)
		)
	)
	(label "B.DQS1_P"
		(at 213.36 80.01 180)
		(effects
			(font
				(size 1.27 1.27)
			)
			(justify right bottom)
		)
	)
	(label "HSA"
		(at 266.065 220.98 0)
		(effects
			(font
				(size 1.27 1.27)
			)
			(justify left bottom)
		)
	)
	(label "B.DQ0"
		(at 213.36 53.34 180)
		(effects
			(font
				(size 1.27 1.27)
			)
			(justify right bottom)
		)
	)
	(label "B.DQS4_P"
		(at 157.48 106.68 0)
		(effects
			(font
				(size 1.27 1.27)
			)
			(justify left bottom)
		)
	)
	(label "B.CK0_N"
		(at 157.48 55.88 0)
		(effects
			(font
				(size 1.27 1.27)
			)
			(justify left bottom)
		)
	)
	(label "B.DQ3"
		(at 213.36 60.96 180)
		(effects
			(font
				(size 1.27 1.27)
			)
			(justify right bottom)
		)
	)
	(label "VSS_DET2"
		(at 278.13 81.28 0)
		(effects
			(font
				(size 1.27 1.27)
			)
			(justify left bottom)
		)
	)
	(label "A.DQS4_P"
		(at 49.53 106.68 0)
		(effects
			(font
				(size 1.27 1.27)
			)
			(justify left bottom)
		)
	)
	(label "B.~{CS1}"
		(at 157.48 49.53 0)
		(effects
			(font
				(size 1.27 1.27)
			)
			(justify left bottom)
		)
	)
	(label "B.CA4"
		(at 157.48 78.74 0)
		(effects
			(font
				(size 1.27 1.27)
			)
			(justify left bottom)
		)
	)
	(label "A.DQ9"
		(at 105.41 88.9 180)
		(effects
			(font
				(size 1.27 1.27)
			)
			(justify right bottom)
		)
	)
	(label "A.CA5"
		(at 49.53 81.28 0)
		(effects
			(font
				(size 1.27 1.27)
			)
			(justify left bottom)
		)
	)
	(label "A.CA0"
		(at 49.53 68.58 0)
		(effects
			(font
				(size 1.27 1.27)
			)
			(justify left bottom)
		)
	)
	(label "B.DQS2_N"
		(at 213.36 115.57 180)
		(effects
			(font
				(size 1.27 1.27)
			)
			(justify right bottom)
		)
	)
	(label "VSS_DET1"
		(at 278.13 78.74 0)
		(effects
			(font
				(size 1.27 1.27)
			)
			(justify left bottom)
		)
	)
	(label "B.DQ20"
		(at 213.36 129.54 180)
		(effects
			(font
				(size 1.27 1.27)
			)
			(justify right bottom)
		)
	)
	(label "RFU2"
		(at 278.13 72.39 0)
		(effects
			(font
				(size 1.27 1.27)
			)
			(justify left bottom)
		)
	)
	(label "B.DQ13"
		(at 213.36 99.06 180)
		(effects
			(font
				(size 1.27 1.27)
			)
			(justify right bottom)
		)
	)
	(label "B.DQ30"
		(at 213.36 167.64 180)
		(effects
			(font
				(size 1.27 1.27)
			)
			(justify right bottom)
		)
	)
	(label "B.CA3"
		(at 157.48 76.2 0)
		(effects
			(font
				(size 1.27 1.27)
			)
			(justify left bottom)
		)
	)
	(label "B.DQ9"
		(at 213.36 88.9 180)
		(effects
			(font
				(size 1.27 1.27)
			)
			(justify right bottom)
		)
	)
	(label "A.DQ0"
		(at 105.41 53.34 180)
		(effects
			(font
				(size 1.27 1.27)
			)
			(justify right bottom)
		)
	)
	(label "RFU1"
		(at 278.13 69.85 0)
		(effects
			(font
				(size 1.27 1.27)
			)
			(justify left bottom)
		)
	)
	(label "HSA"
		(at 326.39 77.47 180)
		(effects
			(font
				(size 1.27 1.27)
			)
			(justify right bottom)
		)
	)
	(label "A.CB2"
		(at 49.53 119.38 0)
		(effects
			(font
				(size 1.27 1.27)
			)
			(justify left bottom)
		)
	)
	(label "A.DQ17"
		(at 105.41 121.92 180)
		(effects
			(font
				(size 1.27 1.27)
			)
			(justify right bottom)
		)
	)
	(label "A.DQ28"
		(at 105.41 162.56 180)
		(effects
			(font
				(size 1.27 1.27)
			)
			(justify right bottom)
		)
	)
	(label "B.DQS3_P"
		(at 213.36 146.05 180)
		(effects
			(font
				(size 1.27 1.27)
			)
			(justify right bottom)
		)
	)
	(label "B.DQS0_P"
		(at 213.36 46.99 180)
		(effects
			(font
				(size 1.27 1.27)
			)
			(justify right bottom)
		)
	)
	(label "B.CA11"
		(at 157.48 96.52 0)
		(effects
			(font
				(size 1.27 1.27)
			)
			(justify left bottom)
		)
	)
	(label "DDR.SCL"
		(at 318.135 80.01 0)
		(effects
			(font
				(size 1.27 1.27)
			)
			(justify left bottom)
		)
	)
	(label "B.DQ1"
		(at 213.36 55.88 180)
		(effects
			(font
				(size 1.27 1.27)
			)
			(justify right bottom)
		)
	)
	(label "B.~{DM3}"
		(at 213.279 173.99 180)
		(effects
			(font
				(size 1.27 1.27)
			)
			(justify right bottom)
		)
	)
	(label "B.DQ14"
		(at 213.36 101.6 180)
		(effects
			(font
				(size 1.27 1.27)
			)
			(justify right bottom)
		)
	)
	(label "B.CK0_P"
		(at 157.48 53.34 0)
		(effects
			(font
				(size 1.27 1.27)
			)
			(justify left bottom)
		)
	)
	(label "B.DQS2_P"
		(at 213.36 113.03 180)
		(effects
			(font
				(size 1.27 1.27)
			)
			(justify right bottom)
		)
	)
	(label "B.DQ8"
		(at 213.36 86.36 180)
		(effects
			(font
				(size 1.27 1.27)
			)
			(justify right bottom)
		)
	)
	(label "B.CB0"
		(at 157.48 114.3 0)
		(effects
			(font
				(size 1.27 1.27)
			)
			(justify left bottom)
		)
	)
	(label "B.CB3"
		(at 157.48 121.92 0)
		(effects
			(font
				(size 1.27 1.27)
			)
			(justify left bottom)
		)
	)
	(label "B.CB1"
		(at 157.48 116.84 0)
		(effects
			(font
				(size 1.27 1.27)
			)
			(justify left bottom)
		)
	)
	(label "B.CA1"
		(at 157.48 71.12 0)
		(effects
			(font
				(size 1.27 1.27)
			)
			(justify left bottom)
		)
	)
	(label "RFU3"
		(at 344.805 126.365 0)
		(effects
			(font
				(size 1.27 1.27)
			)
			(justify left bottom)
		)
	)
	(label "A.DQ18"
		(at 105.1604 124.46 180)
		(effects
			(font
				(size 1.27 1.27)
			)
			(justify right bottom)
		)
	)
	(label "A.DQ22"
		(at 105.41 134.62 180)
		(effects
			(font
				(size 1.27 1.27)
			)
			(justify right bottom)
		)
	)
	(label "A.CA1"
		(at 49.53 71.12 0)
		(effects
			(font
				(size 1.27 1.27)
			)
			(justify left bottom)
		)
	)
	(label "A.DQS0_N"
		(at 105.41 49.53 180)
		(effects
			(font
				(size 1.27 1.27)
			)
			(justify right bottom)
		)
	)
	(label "A.CB0"
		(at 49.53 114.3 0)
		(effects
			(font
				(size 1.27 1.27)
			)
			(justify left bottom)
		)
	)
	(label "A.DQ30"
		(at 105.41 167.64 180)
		(effects
			(font
				(size 1.27 1.27)
			)
			(justify right bottom)
		)
	)
	(label "B.~{DM2}"
		(at 213.36 140.97 180)
		(effects
			(font
				(size 1.27 1.27)
			)
			(justify right bottom)
		)
	)
	(label "B.CA5"
		(at 157.48 81.28 0)
		(effects
			(font
				(size 1.27 1.27)
			)
			(justify left bottom)
		)
	)
	(label "B.DQ17"
		(at 213.36 121.92 180)
		(effects
			(font
				(size 1.27 1.27)
			)
			(justify right bottom)
		)
	)
	(label "A.DQS3_N"
		(at 105.41 148.59 180)
		(effects
			(font
				(size 1.27 1.27)
			)
			(justify right bottom)
		)
	)
	(label "B.~{DM0}"
		(at 213.36 74.93 180)
		(effects
			(font
				(size 1.27 1.27)
			)
			(justify right bottom)
		)
	)
	(label "DDR.SDA"
		(at 318.135 82.55 0)
		(effects
			(font
				(size 1.27 1.27)
			)
			(justify left bottom)
		)
	)
	(label "A.DQS2_P"
		(at 105.41 113.03 180)
		(effects
			(font
				(size 1.27 1.27)
			)
			(justify right bottom)
		)
	)
	(label "B.~{CS0}"
		(at 157.48 46.99 0)
		(effects
			(font
				(size 1.27 1.27)
			)
			(justify left bottom)
		)
	)
	(label "B.DQ2"
		(at 213.36 58.42 180)
		(effects
			(font
				(size 1.27 1.27)
			)
			(justify right bottom)
		)
	)
	(label "B.DQ18"
		(at 213.1104 124.46 180)
		(effects
			(font
				(size 1.27 1.27)
			)
			(justify right bottom)
		)
	)
	(label "A.~{DM2}"
		(at 105.41 140.97 180)
		(effects
			(font
				(size 1.27 1.27)
			)
			(justify right bottom)
		)
	)
	(label "Control.PWR_EN"
		(at 356.87 66.04 180)
		(effects
			(font
				(size 1.27 1.27)
			)
			(justify right bottom)
		)
	)
	(label "Control.PWR_GOOD"
		(at 356.87 71.12 180)
		(effects
			(font
				(size 1.27 1.27)
			)
			(justify right bottom)
		)
	)
	(label "B.DQ15"
		(at 213.36 104.14 180)
		(effects
			(font
				(size 1.27 1.27)
			)
			(justify right bottom)
		)
	)
	(label "B.DQ31"
		(at 213.36 170.18 180)
		(effects
			(font
				(size 1.27 1.27)
			)
			(justify right bottom)
		)
	)
	(label "A.DQ16"
		(at 105.41 119.38 180)
		(effects
			(font
				(size 1.27 1.27)
			)
			(justify right bottom)
		)
	)
	(label "A.DQS4_N"
		(at 49.53 109.22 0)
		(effects
			(font
				(size 1.27 1.27)
			)
			(justify left bottom)
		)
	)
	(label "A.DQS0_P"
		(at 105.41 46.99 180)
		(effects
			(font
				(size 1.27 1.27)
			)
			(justify right bottom)
		)
	)
	(label "A.DQ19"
		(at 105.41 127 180)
		(effects
			(font
				(size 1.27 1.27)
			)
			(justify right bottom)
		)
	)
	(label "A.DQ11"
		(at 105.41 93.98 180)
		(effects
			(font
				(size 1.27 1.27)
			)
			(justify right bottom)
		)
	)
	(label "A.DQ24"
		(at 105.41 152.4 180)
		(effects
			(font
				(size 1.27 1.27)
			)
			(justify right bottom)
		)
	)
	(label "B.DQ21"
		(at 213.36 132.08 180)
		(effects
			(font
				(size 1.27 1.27)
			)
			(justify right bottom)
		)
	)
	(label "A.DQ6"
		(at 105.41 68.58 180)
		(effects
			(font
				(size 1.27 1.27)
			)
			(justify right bottom)
		)
	)
	(label "A.DQ8"
		(at 105.41 86.36 180)
		(effects
			(font
				(size 1.27 1.27)
			)
			(justify right bottom)
		)
	)
	(label "B.DQ28"
		(at 213.36 162.56 180)
		(effects
			(font
				(size 1.27 1.27)
			)
			(justify right bottom)
		)
	)
	(label "B.DQ4"
		(at 213.36 63.5 180)
		(effects
			(font
				(size 1.27 1.27)
			)
			(justify right bottom)
		)
	)
	(label "A.DQ20"
		(at 105.41 129.54 180)
		(effects
			(font
				(size 1.27 1.27)
			)
			(justify right bottom)
		)
	)
	(label "A.~{CS0}"
		(at 49.53 46.99 0)
		(effects
			(font
				(size 1.27 1.27)
			)
			(justify left bottom)
		)
	)
	(label "B.DQ5"
		(at 213.36 66.04 180)
		(effects
			(font
				(size 1.27 1.27)
			)
			(justify right bottom)
		)
	)
	(label "A.~{DM3}"
		(at 105.329 173.99 180)
		(effects
			(font
				(size 1.27 1.27)
			)
			(justify right bottom)
		)
	)
	(label "A.CA7"
		(at 49.53 86.36 0)
		(effects
			(font
				(size 1.27 1.27)
			)
			(justify left bottom)
		)
	)
	(label "A.DQ3"
		(at 105.41 60.96 180)
		(effects
			(font
				(size 1.27 1.27)
			)
			(justify right bottom)
		)
	)
	(label "A.CA2"
		(at 49.53 73.66 0)
		(effects
			(font
				(size 1.27 1.27)
			)
			(justify left bottom)
		)
	)
	(label "B.DQ11"
		(at 213.36 93.98 180)
		(effects
			(font
				(size 1.27 1.27)
			)
			(justify right bottom)
		)
	)
	(label "B.CA2"
		(at 157.48 73.66 0)
		(effects
			(font
				(size 1.27 1.27)
			)
			(justify left bottom)
		)
	)
	(label "A.CA10"
		(at 49.53 93.98 0)
		(effects
			(font
				(size 1.27 1.27)
			)
			(justify left bottom)
		)
	)
	(label "B.CA12"
		(at 157.48 99.06 0)
		(effects
			(font
				(size 1.27 1.27)
			)
			(justify left bottom)
		)
	)
	(label "B.DQ23"
		(at 213.36 137.16 180)
		(effects
			(font
				(size 1.27 1.27)
			)
			(justify right bottom)
		)
	)
	(label "RFU2"
		(at 344.805 121.92 0)
		(effects
			(font
				(size 1.27 1.27)
			)
			(justify left bottom)
		)
	)
	(label "B.DQS1_N"
		(at 213.36 82.55 180)
		(effects
			(font
				(size 1.27 1.27)
			)
			(justify right bottom)
		)
	)
	(label "B.DQS0_N"
		(at 213.36 49.53 180)
		(effects
			(font
				(size 1.27 1.27)
			)
			(justify right bottom)
		)
	)
	(label "B.CA8"
		(at 157.48 88.9 0)
		(effects
			(font
				(size 1.27 1.27)
			)
			(justify left bottom)
		)
	)
	(label "A.CB3"
		(at 49.53 121.92 0)
		(effects
			(font
				(size 1.27 1.27)
			)
			(justify left bottom)
		)
	)
	(label "VSS_DET2"
		(at 254 123.825 0)
		(effects
			(font
				(size 1.27 1.27)
			)
			(justify left bottom)
		)
	)
	(label "A.DQ7"
		(at 105.41 71.12 180)
		(effects
			(font
				(size 1.27 1.27)
			)
			(justify right bottom)
		)
	)
	(label "B.DQS4_N"
		(at 157.48 109.22 0)
		(effects
			(font
				(size 1.27 1.27)
			)
			(justify left bottom)
		)
	)
	(label "A.DQ1"
		(at 105.41 55.88 180)
		(effects
			(font
				(size 1.27 1.27)
			)
			(justify right bottom)
		)
	)
	(label "RFU3"
		(at 278.13 74.93 0)
		(effects
			(font
				(size 1.27 1.27)
			)
			(justify left bottom)
		)
	)
	(label "B.DQ22"
		(at 213.36 134.62 180)
		(effects
			(font
				(size 1.27 1.27)
			)
			(justify right bottom)
		)
	)
	(label "B.DQ16"
		(at 213.36 119.38 180)
		(effects
			(font
				(size 1.27 1.27)
			)
			(justify right bottom)
		)
	)
	(label "B.DQ19"
		(at 213.36 127 180)
		(effects
			(font
				(size 1.27 1.27)
			)
			(justify right bottom)
		)
	)
	(label "A.CA4"
		(at 49.53 78.74 0)
		(effects
			(font
				(size 1.27 1.27)
			)
			(justify left bottom)
		)
	)
	(label "A.DQ4"
		(at 105.41 63.5 180)
		(effects
			(font
				(size 1.27 1.27)
			)
			(justify right bottom)
		)
	)
	(label "A.DQ2"
		(at 105.41 58.42 180)
		(effects
			(font
				(size 1.27 1.27)
			)
			(justify right bottom)
		)
	)
	(label "A.DQ27"
		(at 105.41 160.02 180)
		(effects
			(font
				(size 1.27 1.27)
			)
			(justify right bottom)
		)
	)
	(label "B.CA0"
		(at 157.48 68.58 0)
		(effects
			(font
				(size 1.27 1.27)
			)
			(justify left bottom)
		)
	)
	(label "B.DQ25"
		(at 213.36 154.94 180)
		(effects
			(font
				(size 1.27 1.27)
			)
			(justify right bottom)
		)
	)
	(label "A.DQ26"
		(at 105.41 157.48 180)
		(effects
			(font
				(size 1.27 1.27)
			)
			(justify right bottom)
		)
	)
	(label "A.DQS1_P"
		(at 105.41 80.01 180)
		(effects
			(font
				(size 1.27 1.27)
			)
			(justify right bottom)
		)
	)
	(label "A.CA11"
		(at 49.53 96.52 0)
		(effects
			(font
				(size 1.27 1.27)
			)
			(justify left bottom)
		)
	)
	(label "A.DQ25"
		(at 105.41 154.94 180)
		(effects
			(font
				(size 1.27 1.27)
			)
			(justify right bottom)
		)
	)
	(label "Control.~{ALERT}"
		(at 356.87 73.66 180)
		(effects
			(font
				(size 1.27 1.27)
			)
			(justify right bottom)
		)
	)
	(label "Control.~{RESET}"
		(at 356.87 68.58 180)
		(effects
			(font
				(size 1.27 1.27)
			)
			(justify right bottom)
		)
	)
	(label "A.CA3"
		(at 49.53 76.2 0)
		(effects
			(font
				(size 1.27 1.27)
			)
			(justify left bottom)
		)
	)
	(label "A.DQ21"
		(at 105.41 132.08 180)
		(effects
			(font
				(size 1.27 1.27)
			)
			(justify right bottom)
		)
	)
	(label "A.DQ14"
		(at 105.41 101.6 180)
		(effects
			(font
				(size 1.27 1.27)
			)
			(justify right bottom)
		)
	)
	(global_label "HOT_SWAP_YELLOW"
		(shape input)
		(at 58.42 247.65 180)
		(fields_autoplaced yes)
		(effects
			(font
				(size 1.27 1.27)
			)
			(justify right)
		)
		(property "Intersheetrefs" "${INTERSHEET_REFS}"
			(at 38.4368 247.5706 0)
			(effects
				(font
					(size 1.27 1.27)
				)
				(justify right)
			)
		)
	)
	(global_label "HOT_SWAP_GREEN"
		(shape input)
		(at 58.42 237.49 180)
		(fields_autoplaced yes)
		(effects
			(font
				(size 1.27 1.27)
			)
			(justify right)
		)
		(property "Intersheetrefs" "${INTERSHEET_REFS}"
			(at 39.3439 237.4106 0)
			(effects
				(font
					(size 1.27 1.27)
				)
				(justify right)
			)
		)
	)
	(global_label "HOT_SWAP_RED"
		(shape input)
		(at 58.42 227.33 180)
		(fields_autoplaced yes)
		(effects
			(font
				(size 1.27 1.27)
			)
			(justify right)
		)
		(property "Intersheetrefs" "${INTERSHEET_REFS}"
			(at 41.8234 227.2506 0)
			(effects
				(font
					(size 1.27 1.27)
				)
				(justify right)
			)
		)
	)
	(global_label "RFU_3"
		(shape input)
		(at 379.73 126.365 0)
		(fields_autoplaced yes)
		(effects
			(font
				(size 1.27 1.27)
			)
			(justify left)
		)
		(property "Intersheetrefs" "${INTERSHEET_REFS}"
			(at 387.9204 126.2856 0)
			(effects
				(font
					(size 1.27 1.27)
				)
				(justify left)
			)
		)
	)
	(global_label "TB_DETECT"
		(shape input)
		(at 283.845 123.825 0)
		(fields_autoplaced yes)
		(effects
			(font
				(size 1.27 1.27)
			)
			(justify left)
		)
		(property "Intersheetrefs" "${INTERSHEET_REFS}"
			(at 296.1478 123.7456 0)
			(effects
				(font
					(size 1.27 1.27)
				)
				(justify left)
			)
		)
	)
	(global_label "RFU_2"
		(shape input)
		(at 379.73 121.92 0)
		(fields_autoplaced yes)
		(effects
			(font
				(size 1.27 1.27)
			)
			(justify left)
		)
		(property "Intersheetrefs" "${INTERSHEET_REFS}"
			(at 387.9204 121.8406 0)
			(effects
				(font
					(size 1.27 1.27)
				)
				(justify left)
			)
		)
	)
	(global_label "~{DDR_PRESENCE}"
		(shape input)
		(at 283.845 120.65 0)
		(fields_autoplaced yes)
		(effects
			(font
				(size 1.27 1.27)
			)
			(justify left)
		)
		(property "Intersheetrefs" "${INTERSHEET_REFS}"
			(at 300.744 120.5706 0)
			(effects
				(font
					(size 1.27 1.27)
				)
				(justify left)
			)
		)
	)
	(global_label "RFU_1"
		(shape input)
		(at 379.73 117.475 0)
		(fields_autoplaced yes)
		(effects
			(font
				(size 1.27 1.27)
			)
			(justify left)
		)
		(property "Intersheetrefs" "${INTERSHEET_REFS}"
			(at 387.9204 117.3956 0)
			(effects
				(font
					(size 1.27 1.27)
				)
				(justify left)
			)
		)
	)
	(global_label "HOT_SWAP_BUTTON"
		(shape input)
		(at 180.34 214.63 0)
		(fields_autoplaced yes)
		(effects
			(font
				(size 1.27 1.27)
			)
			(justify left)
		)
		(property "Intersheetrefs" "${INTERSHEET_REFS}"
			(at 200.4442 214.5506 0)
			(effects
				(font
					(size 1.27 1.27)
				)
				(justify left)
			)
		)
	)
	(hierarchical_label "DDR{I^{2}C}"
		(shape bidirectional)
		(at 331.47 75.565 0)
		(effects
			(font
				(size 1.27 1.27)
			)
			(justify left)
		)
	)
	(hierarchical_label "B{DDR5}"
		(shape input)
		(at 218.44 42.545 0)
		(effects
			(font
				(size 1.27 1.27)
			)
			(justify left)
		)
	)
	(hierarchical_label "Control{DDR5}"
		(shape input)
		(at 361.95 61.595 0)
		(effects
			(font
				(size 1.27 1.27)
			)
			(justify left)
		)
	)
	(hierarchical_label "B{DDR5}"
		(shape input)
		(at 152.4 42.545 180)
		(effects
			(font
				(size 1.27 1.27)
			)
			(justify right)
		)
	)
	(hierarchical_label "A{DDR5}"
		(shape input)
		(at 110.49 42.545 0)
		(effects
			(font
				(size 1.27 1.27)
			)
			(justify left)
		)
	)
	(hierarchical_label "A{DDR5}"
		(shape input)
		(at 44.45 42.545 180)
		(effects
			(font
				(size 1.27 1.27)
			)
			(justify right)
		)
	)
	(symbol
		(lib_id "antmicroResistors0402:R_330R_0402")
		(at 104.14 212.09 270)
		(unit 1)
		(exclude_from_sim no)
		(in_bom yes)
		(on_board yes)
		(dnp no)
		(fields_autoplaced yes)
		(property "Reference" "R63"
			(at 106.68 213.36 90)
			(effects
				(font
					(size 1.27 1.27)
				)
				(justify left)
			)
		)
		(property "Value" "R_330R_0402"
			(at 91.44 232.41 0)
			(effects
				(font
					(size 1.27 1.27)
					(thickness 0.15)
				)
				(justify left bottom)
				(hide yes)
			)
		)
		(property "Footprint" "antmicro-footprints:R_0402_1005Metric"
			(at 88.9 232.41 0)
			(effects
				(font
					(size 1.27 1.27)
					(thickness 0.15)
				)
				(justify left bottom)
				(hide yes)
			)
		)
		(property "Datasheet" "https://www.bourns.com/docs/product-datasheets/cr.pdf"
			(at 86.36 232.41 0)
			(effects
				(font
					(size 1.27 1.27)
					(thickness 0.15)
				)
				(justify left bottom)
				(hide yes)
			)
		)
		(property "Description" ""
			(at 104.14 212.09 0)
			(effects
				(font
					(size 1.27 1.27)
				)
			)
		)
		(property "Manufacturer" "Bourns"
			(at 81.28 232.41 0)
			(effects
				(font
					(size 1.27 1.27)
					(thickness 0.15)
				)
				(justify left bottom)
				(hide yes)
			)
		)
		(property "MPN" "CR0402-FX-3300GLF"
			(at 83.82 232.41 0)
			(effects
				(font
					(size 1.27 1.27)
					(thickness 0.15)
				)
				(justify left bottom)
				(hide yes)
			)
		)
		(property "Val" "330R"
			(at 106.68 216.5349 90)
			(effects
				(font
					(size 1.27 1.27)
					(thickness 0.15)
				)
				(justify left)
			)
		)
		(property "License" "Apache-2.0"
			(at 78.74 232.41 0)
			(effects
				(font
					(size 1.27 1.27)
					(thickness 0.15)
				)
				(justify left bottom)
				(hide yes)
			)
		)
		(property "Author" "Antmicro"
			(at 76.2 232.41 0)
			(effects
				(font
					(size 1.27 1.27)
					(thickness 0.15)
				)
				(justify left bottom)
				(hide yes)
			)
		)
		(property "Tolerance" "1%"
			(at 93.98 232.41 0)
			(effects
				(font
					(size 1.27 1.27)
				)
				(justify left bottom)
				(hide yes)
			)
		)
		(pin "1"
		)
		(pin "2"
		)
		(instances
			(project "sodimm-ddr5-tester"
				(path ""
					(reference "R63")
					(unit 1)
				)
			)
		)
	)
	(symbol
		(lib_id "antmicropower:+3V3")
		(at 36.83 205.74 0)
		(unit 1)
		(exclude_from_sim no)
		(in_bom yes)
		(on_board yes)
		(dnp no)
		(property "Reference" "#PWR0199"
			(at 36.83 209.55 0)
			(effects
				(font
					(size 1.27 1.27)
				)
				(hide yes)
			)
		)
		(property "Value" "+3V3"
			(at 33.655 203.2 0)
			(effects
				(font
					(size 1.27 1.27)
					(thickness 0.15)
				)
				(justify left bottom)
			)
		)
		(property "Footprint" ""
			(at 52.07 213.36 0)
			(effects
				(font
					(size 1.27 1.27)
					(thickness 0.15)
				)
				(justify left bottom)
				(hide yes)
			)
		)
		(property "Datasheet" ""
			(at 52.07 215.9 0)
			(effects
				(font
					(size 1.27 1.27)
					(thickness 0.15)
				)
				(justify left bottom)
				(hide yes)
			)
		)
		(property "Description" ""
			(at 36.83 205.74 0)
			(effects
				(font
					(size 1.27 1.27)
				)
			)
		)
		(property "Author" "Antmicro"
			(at 52.07 208.28 0)
			(effects
				(font
					(size 1.27 1.27)
					(thickness 0.15)
				)
				(justify left bottom)
				(hide yes)
			)
		)
		(property "License" "Apache-2.0"
			(at 52.07 210.82 0)
			(effects
				(font
					(size 1.27 1.27)
					(thickness 0.15)
				)
				(justify left bottom)
				(hide yes)
			)
		)
		(pin "1"
		)
		(instances
			(project "sodimm-ddr5-tester"
				(path ""
					(reference "#PWR0199")
					(unit 1)
				)
			)
		)
	)
	(symbol
		(lib_id "antmicropower:GND")
		(at 361.95 224.79 0)
		(unit 1)
		(exclude_from_sim no)
		(in_bom yes)
		(on_board yes)
		(dnp no)
		(property "Reference" "#PWR049"
			(at 361.95 231.14 0)
			(effects
				(font
					(size 1.27 1.27)
				)
				(hide yes)
			)
		)
		(property "Value" "GND"
			(at 360.426 228.6 0)
			(effects
				(font
					(size 1.27 1.27)
					(thickness 0.15)
				)
				(justify left)
			)
		)
		(property "Footprint" ""
			(at 370.84 232.41 0)
			(effects
				(font
					(size 1.27 1.27)
					(thickness 0.15)
				)
				(justify left bottom)
				(hide yes)
			)
		)
		(property "Datasheet" ""
			(at 370.84 237.49 0)
			(effects
				(font
					(size 1.27 1.27)
					(thickness 0.15)
				)
				(justify left bottom)
				(hide yes)
			)
		)
		(property "Description" ""
			(at 370.84 240.03 0)
			(effects
				(font
					(size 1.27 1.27)
				)
				(justify left bottom)
				(hide yes)
			)
		)
		(property "Author" "Antmicro"
			(at 370.84 232.41 0)
			(effects
				(font
					(size 1.27 1.27)
					(thickness 0.15)
				)
				(justify left bottom)
				(hide yes)
			)
		)
		(property "License" "Apache-2.0"
			(at 370.84 234.95 0)
			(effects
				(font
					(size 1.27 1.27)
					(thickness 0.15)
				)
				(justify left bottom)
				(hide yes)
			)
		)
		(pin "1"
		)
		(instances
			(project "sodimm-ddr5-tester"
				(path ""
					(reference "#PWR049")
					(unit 1)
				)
			)
		)
	)
	(symbol
		(lib_id "antmicroResistors0402:R_0R_0402")
		(at 275.59 120.65 0)
		(unit 1)
		(exclude_from_sim no)
		(in_bom yes)
		(on_board yes)
		(dnp no)
		(property "Reference" "R27"
			(at 281.94 119.38 0)
			(effects
				(font
					(size 1.27 1.27)
					(thickness 0.15)
				)
			)
		)
		(property "Value" "R_0R_0402"
			(at 295.91 133.35 0)
			(effects
				(font
					(size 1.27 1.27)
					(thickness 0.15)
				)
				(justify left bottom)
				(hide yes)
			)
		)
		(property "Footprint" "antmicro-footprints:R_0402_1005Metric"
			(at 295.91 135.89 0)
			(effects
				(font
					(size 1.27 1.27)
					(thickness 0.15)
				)
				(justify left bottom)
				(hide yes)
			)
		)
		(property "Datasheet" "https://industrial.panasonic.com/cdbs/www-data/pdf/RDA0000/AOA0000C301.pdf"
			(at 295.91 138.43 0)
			(effects
				(font
					(size 1.27 1.27)
					(thickness 0.15)
				)
				(justify left bottom)
				(hide yes)
			)
		)
		(property "Description" ""
			(at 275.59 120.65 0)
			(effects
				(font
					(size 1.27 1.27)
				)
			)
		)
		(property "MPN" "ERJ2GE0R00X"
			(at 295.91 140.97 0)
			(effects
				(font
					(size 1.27 1.27)
					(thickness 0.15)
				)
				(justify left bottom)
				(hide yes)
			)
		)
		(property "Manufacturer" "Panasonic"
			(at 295.91 143.51 0)
			(effects
				(font
					(size 1.27 1.27)
					(thickness 0.15)
				)
				(justify left bottom)
				(hide yes)
			)
		)
		(property "License" "Apache-2.0"
			(at 295.91 146.05 0)
			(effects
				(font
					(size 1.27 1.27)
					(thickness 0.15)
				)
				(justify left bottom)
				(hide yes)
			)
		)
		(property "Author" "Antmicro"
			(at 295.91 148.59 0)
			(effects
				(font
					(size 1.27 1.27)
					(thickness 0.15)
				)
				(justify left bottom)
				(hide yes)
			)
		)
		(property "Val" "0R"
			(at 274.32 119.38 0)
			(effects
				(font
					(size 1.27 1.27)
					(thickness 0.15)
				)
			)
		)
		(property "Tolerance" "~"
			(at 295.91 130.81 0)
			(effects
				(font
					(size 1.27 1.27)
				)
				(justify left bottom)
				(hide yes)
			)
		)
		(property "Current" "1A"
			(at 295.91 151.13 0)
			(effects
				(font
					(size 1.27 1.27)
					(thickness 0.15)
				)
				(justify left bottom)
				(hide yes)
			)
		)
		(pin "1"
		)
		(pin "2"
		)
		(instances
			(project "sodimm-ddr5-tester"
				(path ""
					(reference "R27")
					(unit 1)
				)
			)
		)
	)
	(symbol
		(lib_id "antmicropower:+5V")
		(at 267.97 51.435 0)
		(unit 1)
		(exclude_from_sim no)
		(in_bom yes)
		(on_board yes)
		(dnp no)
		(fields_autoplaced yes)
		(property "Reference" "#PWR035"
			(at 267.97 55.245 0)
			(effects
				(font
					(size 1.27 1.27)
				)
				(hide yes)
			)
		)
		(property "Value" "+5V"
			(at 267.97 47.8606 0)
			(effects
				(font
					(size 1.27 1.27)
					(thickness 0.15)
				)
			)
		)
		(property "Footprint" ""
			(at 283.21 59.055 0)
			(effects
				(font
					(size 1.27 1.27)
					(thickness 0.15)
				)
				(justify left bottom)
				(hide yes)
			)
		)
		(property "Datasheet" ""
			(at 283.21 61.595 0)
			(effects
				(font
					(size 1.27 1.27)
					(thickness 0.15)
				)
				(justify left bottom)
				(hide yes)
			)
		)
		(property "Description" ""
			(at 267.97 51.435 0)
			(effects
				(font
					(size 1.27 1.27)
				)
			)
		)
		(property "Author" "Antmicro"
			(at 283.21 59.055 0)
			(effects
				(font
					(size 1.27 1.27)
					(thickness 0.15)
				)
				(justify left bottom)
				(hide yes)
			)
		)
		(property "License" "Apache-2.0"
			(at 283.21 61.595 0)
			(effects
				(font
					(size 1.27 1.27)
					(thickness 0.15)
				)
				(justify left bottom)
				(hide yes)
			)
		)
		(pin "1"
		)
		(instances
			(project "sodimm-ddr5-tester"
				(path ""
					(reference "#PWR035")
					(unit 1)
				)
			)
		)
	)
	(symbol
		(lib_id "antmicroResistors0402:R_47k_0402")
		(at 271.78 116.205 90)
		(unit 1)
		(exclude_from_sim no)
		(in_bom yes)
		(on_board yes)
		(dnp no)
		(fields_autoplaced yes)
		(property "Reference" "R25"
			(at 273.431 112.8344 90)
			(effects
				(font
					(size 1.27 1.27)
					(thickness 0.15)
				)
				(justify right)
			)
		)
		(property "Value" "R_47k_0402"
			(at 284.48 95.885 0)
			(effects
				(font
					(size 1.27 1.27)
					(thickness 0.15)
				)
				(justify left bottom)
				(hide yes)
			)
		)
		(property "Footprint" "antmicro-footprints:R_0402_1005Metric"
			(at 287.02 95.885 0)
			(effects
				(font
					(size 1.27 1.27)
					(thickness 0.15)
				)
				(justify left bottom)
				(hide yes)
			)
		)
		(property "Datasheet" "https://www.bourns.com/docs/product-datasheets/cr.pdf"
			(at 289.56 95.885 0)
			(effects
				(font
					(size 1.27 1.27)
					(thickness 0.15)
				)
				(justify left bottom)
				(hide yes)
			)
		)
		(property "Description" ""
			(at 271.78 116.205 0)
			(effects
				(font
					(size 1.27 1.27)
				)
			)
		)
		(property "MPN" "CR0402-FX-4702GLF"
			(at 292.1 95.885 0)
			(effects
				(font
					(size 1.27 1.27)
					(thickness 0.15)
				)
				(justify left bottom)
				(hide yes)
			)
		)
		(property "Manufacturer" "Bourns"
			(at 294.64 95.885 0)
			(effects
				(font
					(size 1.27 1.27)
					(thickness 0.15)
				)
				(justify left bottom)
				(hide yes)
			)
		)
		(property "License" "Apache-2.0"
			(at 297.18 95.885 0)
			(effects
				(font
					(size 1.27 1.27)
					(thickness 0.15)
				)
				(justify left bottom)
				(hide yes)
			)
		)
		(property "Author" "Antmicro"
			(at 299.72 95.885 0)
			(effects
				(font
					(size 1.27 1.27)
					(thickness 0.15)
				)
				(justify left bottom)
				(hide yes)
			)
		)
		(property "Val" "47k"
			(at 273.431 115.3581 90)
			(effects
				(font
					(size 1.27 1.27)
					(thickness 0.15)
				)
				(justify right)
			)
		)
		(property "Tolerance" "1%"
			(at 281.94 95.885 0)
			(effects
				(font
					(size 1.27 1.27)
				)
				(justify left bottom)
				(hide yes)
			)
		)
		(pin "1"
		)
		(pin "2"
		)
		(instances
			(project "sodimm-ddr5-tester"
				(path ""
					(reference "R25")
					(unit 1)
				)
			)
		)
	)
	(symbol
		(lib_id "antmicropower:GND")
		(at 271.78 136.525 0)
		(unit 1)
		(exclude_from_sim no)
		(in_bom yes)
		(on_board yes)
		(dnp no)
		(property "Reference" "#PWR034"
			(at 271.78 142.875 0)
			(effects
				(font
					(size 1.27 1.27)
				)
				(hide yes)
			)
		)
		(property "Value" "GND"
			(at 270.002 140.716 0)
			(effects
				(font
					(size 1.27 1.27)
					(thickness 0.15)
				)
				(justify left)
			)
		)
		(property "Footprint" ""
			(at 280.67 144.145 0)
			(effects
				(font
					(size 1.27 1.27)
					(thickness 0.15)
				)
				(justify left bottom)
				(hide yes)
			)
		)
		(property "Datasheet" ""
			(at 280.67 149.225 0)
			(effects
				(font
					(size 1.27 1.27)
					(thickness 0.15)
				)
				(justify left bottom)
				(hide yes)
			)
		)
		(property "Description" ""
			(at 280.67 151.765 0)
			(effects
				(font
					(size 1.27 1.27)
				)
				(justify left bottom)
				(hide yes)
			)
		)
		(property "Author" "Antmicro"
			(at 280.67 144.145 0)
			(effects
				(font
					(size 1.27 1.27)
					(thickness 0.15)
				)
				(justify left bottom)
				(hide yes)
			)
		)
		(property "License" "Apache-2.0"
			(at 280.67 146.685 0)
			(effects
				(font
					(size 1.27 1.27)
					(thickness 0.15)
				)
				(justify left bottom)
				(hide yes)
			)
		)
		(pin "1"
		)
		(instances
			(project "sodimm-ddr5-tester"
				(path ""
					(reference "#PWR034")
					(unit 1)
				)
			)
		)
	)
	(symbol
		(lib_id "antmicropower:GND")
		(at 164.465 234.95 0)
		(unit 1)
		(exclude_from_sim no)
		(in_bom yes)
		(on_board yes)
		(dnp no)
		(property "Reference" "#PWR0211"
			(at 164.465 241.3 0)
			(effects
				(font
					(size 1.27 1.27)
				)
				(hide yes)
			)
		)
		(property "Value" "GND"
			(at 162.56 239.014 0)
			(effects
				(font
					(size 1.27 1.27)
					(thickness 0.15)
				)
				(justify left)
			)
		)
		(property "Footprint" ""
			(at 173.355 242.57 0)
			(effects
				(font
					(size 1.27 1.27)
					(thickness 0.15)
				)
				(justify left bottom)
				(hide yes)
			)
		)
		(property "Datasheet" ""
			(at 173.355 247.65 0)
			(effects
				(font
					(size 1.27 1.27)
					(thickness 0.15)
				)
				(justify left bottom)
				(hide yes)
			)
		)
		(property "Description" ""
			(at 173.355 250.19 0)
			(effects
				(font
					(size 1.27 1.27)
				)
				(justify left bottom)
				(hide yes)
			)
		)
		(property "Author" "Antmicro"
			(at 173.355 242.57 0)
			(effects
				(font
					(size 1.27 1.27)
					(thickness 0.15)
				)
				(justify left bottom)
				(hide yes)
			)
		)
		(property "License" "Apache-2.0"
			(at 173.355 245.11 0)
			(effects
				(font
					(size 1.27 1.27)
					(thickness 0.15)
				)
				(justify left bottom)
				(hide yes)
			)
		)
		(pin "1"
		)
		(instances
			(project "sodimm-ddr5-tester"
				(path ""
					(reference "#PWR0211")
					(unit 1)
				)
			)
		)
	)
	(symbol
		(lib_id "antmicroResistors0402:R_0R_0402")
		(at 328.93 66.04 0)
		(unit 1)
		(exclude_from_sim no)
		(in_bom yes)
		(on_board yes)
		(dnp no)
		(property "Reference" "R38"
			(at 335.28 64.77 0)
			(effects
				(font
					(size 1.27 1.27)
					(thickness 0.15)
				)
			)
		)
		(property "Value" "R_0R_0402"
			(at 349.25 78.74 0)
			(effects
				(font
					(size 1.27 1.27)
					(thickness 0.15)
				)
				(justify left bottom)
				(hide yes)
			)
		)
		(property "Footprint" "antmicro-footprints:R_0402_1005Metric"
			(at 349.25 81.28 0)
			(effects
				(font
					(size 1.27 1.27)
					(thickness 0.15)
				)
				(justify left bottom)
				(hide yes)
			)
		)
		(property "Datasheet" "https://industrial.panasonic.com/cdbs/www-data/pdf/RDA0000/AOA0000C301.pdf"
			(at 349.25 83.82 0)
			(effects
				(font
					(size 1.27 1.27)
					(thickness 0.15)
				)
				(justify left bottom)
				(hide yes)
			)
		)
		(property "Description" ""
			(at 328.93 66.04 0)
			(effects
				(font
					(size 1.27 1.27)
				)
			)
		)
		(property "MPN" "ERJ2GE0R00X"
			(at 349.25 86.36 0)
			(effects
				(font
					(size 1.27 1.27)
					(thickness 0.15)
				)
				(justify left bottom)
				(hide yes)
			)
		)
		(property "Manufacturer" "Panasonic"
			(at 349.25 88.9 0)
			(effects
				(font
					(size 1.27 1.27)
					(thickness 0.15)
				)
				(justify left bottom)
				(hide yes)
			)
		)
		(property "License" "Apache-2.0"
			(at 349.25 91.44 0)
			(effects
				(font
					(size 1.27 1.27)
					(thickness 0.15)
				)
				(justify left bottom)
				(hide yes)
			)
		)
		(property "Author" "Antmicro"
			(at 349.25 93.98 0)
			(effects
				(font
					(size 1.27 1.27)
					(thickness 0.15)
				)
				(justify left bottom)
				(hide yes)
			)
		)
		(property "Val" "0R"
			(at 327.66 64.77 0)
			(effects
				(font
					(size 1.27 1.27)
					(thickness 0.15)
				)
			)
		)
		(property "Tolerance" "~"
			(at 349.25 76.2 0)
			(effects
				(font
					(size 1.27 1.27)
				)
				(justify left bottom)
				(hide yes)
			)
		)
		(property "Current" "1A"
			(at 349.25 96.52 0)
			(effects
				(font
					(size 1.27 1.27)
					(thickness 0.15)
				)
				(justify left bottom)
				(hide yes)
			)
		)
		(pin "1"
		)
		(pin "2"
		)
		(instances
			(project "sodimm-ddr5-tester"
				(path ""
					(reference "R38")
					(unit 1)
				)
			)
		)
	)
	(symbol
		(lib_id "antmicroResistors0402:R_0R_0402")
		(at 266.065 134.62 90)
		(unit 1)
		(exclude_from_sim no)
		(in_bom no)
		(on_board yes)
		(dnp yes)
		(property "Reference" "R24"
			(at 264.4141 129.9835 90)
			(effects
				(font
					(size 1.27 1.27)
					(thickness 0.15)
				)
				(justify left)
			)
		)
		(property "Value" "R_0R_0402"
			(at 278.765 114.3 0)
			(effects
				(font
					(size 1.27 1.27)
					(thickness 0.15)
				)
				(justify left bottom)
				(hide yes)
			)
		)
		(property "Footprint" "antmicro-footprints:R_0402_1005Metric"
			(at 281.305 114.3 0)
			(effects
				(font
					(size 1.27 1.27)
					(thickness 0.15)
				)
				(justify left bottom)
				(hide yes)
			)
		)
		(property "Datasheet" "https://industrial.panasonic.com/cdbs/www-data/pdf/RDA0000/AOA0000C301.pdf"
			(at 283.845 114.3 0)
			(effects
				(font
					(size 1.27 1.27)
					(thickness 0.15)
				)
				(justify left bottom)
				(hide yes)
			)
		)
		(property "Description" ""
			(at 266.065 134.62 0)
			(effects
				(font
					(size 1.27 1.27)
				)
			)
		)
		(property "MPN" "ERJ2GE0R00X"
			(at 286.385 114.3 0)
			(effects
				(font
					(size 1.27 1.27)
					(thickness 0.15)
				)
				(justify left bottom)
				(hide yes)
			)
		)
		(property "Manufacturer" "Panasonic"
			(at 288.925 114.3 0)
			(effects
				(font
					(size 1.27 1.27)
					(thickness 0.15)
				)
				(justify left bottom)
				(hide yes)
			)
		)
		(property "License" "Apache-2.0"
			(at 291.465 114.3 0)
			(effects
				(font
					(size 1.27 1.27)
					(thickness 0.15)
				)
				(justify left bottom)
				(hide yes)
			)
		)
		(property "Author" "Antmicro"
			(at 294.005 114.3 0)
			(effects
				(font
					(size 1.27 1.27)
					(thickness 0.15)
				)
				(justify left bottom)
				(hide yes)
			)
		)
		(property "Val" "0R"
			(at 264.4141 132.5072 90)
			(effects
				(font
					(size 1.27 1.27)
					(thickness 0.15)
				)
				(justify left)
			)
		)
		(property "Tolerance" "~"
			(at 276.225 114.3 0)
			(effects
				(font
					(size 1.27 1.27)
				)
				(justify left bottom)
				(hide yes)
			)
		)
		(property "Current" "1A"
			(at 296.545 114.3 0)
			(effects
				(font
					(size 1.27 1.27)
					(thickness 0.15)
				)
				(justify left bottom)
				(hide yes)
			)
		)
		(pin "1"
		)
		(pin "2"
		)
		(instances
			(project "sodimm-ddr5-tester"
				(path ""
					(reference "R24")
					(unit 1)
				)
			)
		)
	)
	(symbol
		(lib_id "antmicropower:GND")
		(at 359.41 138.43 0)
		(unit 1)
		(exclude_from_sim no)
		(in_bom yes)
		(on_board yes)
		(dnp no)
		(property "Reference" "#PWR039"
			(at 359.41 144.78 0)
			(effects
				(font
					(size 1.27 1.27)
				)
				(hide yes)
			)
		)
		(property "Value" "GND"
			(at 357.632 142.748 0)
			(effects
				(font
					(size 1.27 1.27)
					(thickness 0.15)
				)
				(justify left)
			)
		)
		(property "Footprint" ""
			(at 368.3 146.05 0)
			(effects
				(font
					(size 1.27 1.27)
					(thickness 0.15)
				)
				(justify left bottom)
				(hide yes)
			)
		)
		(property "Datasheet" ""
			(at 368.3 151.13 0)
			(effects
				(font
					(size 1.27 1.27)
					(thickness 0.15)
				)
				(justify left bottom)
				(hide yes)
			)
		)
		(property "Description" ""
			(at 368.3 153.67 0)
			(effects
				(font
					(size 1.27 1.27)
				)
				(justify left bottom)
				(hide yes)
			)
		)
		(property "Author" "Antmicro"
			(at 368.3 146.05 0)
			(effects
				(font
					(size 1.27 1.27)
					(thickness 0.15)
				)
				(justify left bottom)
				(hide yes)
			)
		)
		(property "License" "Apache-2.0"
			(at 368.3 148.59 0)
			(effects
				(font
					(size 1.27 1.27)
					(thickness 0.15)
				)
				(justify left bottom)
				(hide yes)
			)
		)
		(pin "1"
		)
		(instances
			(project "sodimm-ddr5-tester"
				(path ""
					(reference "#PWR039")
					(unit 1)
				)
			)
		)
	)
	(symbol
		(lib_id "antmicroResistors0402:R_0R_0402")
		(at 353.695 136.525 90)
		(unit 1)
		(exclude_from_sim no)
		(in_bom no)
		(on_board yes)
		(dnp yes)
		(fields_autoplaced yes)
		(property "Reference" "R29"
			(at 352.425 137.795 0)
			(effects
				(font
					(size 1.27 1.27)
					(thickness 0.15)
				)
			)
		)
		(property "Value" "R_0R_0402"
			(at 366.395 116.205 0)
			(effects
				(font
					(size 1.27 1.27)
					(thickness 0.15)
				)
				(justify left bottom)
				(hide yes)
			)
		)
		(property "Footprint" "antmicro-footprints:R_0402_1005Metric"
			(at 368.935 116.205 0)
			(effects
				(font
					(size 1.27 1.27)
					(thickness 0.15)
				)
				(justify left bottom)
				(hide yes)
			)
		)
		(property "Datasheet" "https://industrial.panasonic.com/cdbs/www-data/pdf/RDA0000/AOA0000C301.pdf"
			(at 371.475 116.205 0)
			(effects
				(font
					(size 1.27 1.27)
					(thickness 0.15)
				)
				(justify left bottom)
				(hide yes)
			)
		)
		(property "Description" ""
			(at 353.695 136.525 0)
			(effects
				(font
					(size 1.27 1.27)
				)
			)
		)
		(property "MPN" "ERJ2GE0R00X"
			(at 374.015 116.205 0)
			(effects
				(font
					(size 1.27 1.27)
					(thickness 0.15)
				)
				(justify left bottom)
				(hide yes)
			)
		)
		(property "Manufacturer" "Panasonic"
			(at 376.555 116.205 0)
			(effects
				(font
					(size 1.27 1.27)
					(thickness 0.15)
				)
				(justify left bottom)
				(hide yes)
			)
		)
		(property "License" "Apache-2.0"
			(at 379.095 116.205 0)
			(effects
				(font
					(size 1.27 1.27)
					(thickness 0.15)
				)
				(justify left bottom)
				(hide yes)
			)
		)
		(property "Author" "Antmicro"
			(at 381.635 116.205 0)
			(effects
				(font
					(size 1.27 1.27)
					(thickness 0.15)
				)
				(justify left bottom)
				(hide yes)
			)
		)
		(property "Val" "0R"
			(at 352.425 130.175 0)
			(effects
				(font
					(size 1.27 1.27)
					(thickness 0.15)
				)
			)
		)
		(property "Tolerance" "~"
			(at 363.855 116.205 0)
			(effects
				(font
					(size 1.27 1.27)
				)
				(justify left bottom)
				(hide yes)
			)
		)
		(property "Current" "1A"
			(at 384.175 116.205 0)
			(effects
				(font
					(size 1.27 1.27)
					(thickness 0.15)
				)
				(justify left bottom)
				(hide yes)
			)
		)
		(pin "1"
		)
		(pin "2"
		)
		(instances
			(project "sodimm-ddr5-tester"
				(path ""
					(reference "R29")
					(unit 1)
				)
			)
		)
	)
	(symbol
		(lib_id "antmicroTransistorsFETsMOSFETsSingle:BSS138PW,115")
		(at 59.69 247.65 0)
		(unit 1)
		(exclude_from_sim no)
		(in_bom yes)
		(on_board yes)
		(dnp no)
		(property "Reference" "Q9"
			(at 69.85 243.84 0)
			(effects
				(font
					(size 1.27 1.27)
					(thickness 0.15)
				)
				(justify left)
			)
		)
		(property "Value" "BSS138PW,115"
			(at 82.55 256.54 0)
			(effects
				(font
					(size 1.27 1.27)
					(thickness 0.15)
				)
				(justify left bottom)
				(hide yes)
			)
		)
		(property "Footprint" "antmicro-footprints:SC70-3"
			(at 82.55 259.08 0)
			(effects
				(font
					(size 1.27 1.27)
					(thickness 0.15)
				)
				(justify left bottom)
				(hide yes)
			)
		)
		(property "Datasheet" "https://assets.nexperia.com/documents/data-sheet/BSS138PW.pdf"
			(at 82.55 261.62 0)
			(effects
				(font
					(size 1.27 1.27)
					(thickness 0.15)
				)
				(justify left bottom)
				(hide yes)
			)
		)
		(property "Description" "Power MOSFET, N Channel, 60 V, 320 mA, 0.9 ohm, SOT-323, Surface Mount"
			(at 82.55 274.32 0)
			(effects
				(font
					(size 1.27 1.27)
				)
				(justify left bottom)
				(hide yes)
			)
		)
		(property "MPN" "BSS138PW,115"
			(at 69.85 246.38 0)
			(effects
				(font
					(size 1.27 1.27)
					(thickness 0.15)
				)
				(justify left)
			)
		)
		(property "Manufacturer" "Nexperia"
			(at 82.55 266.7 0)
			(effects
				(font
					(size 1.27 1.27)
					(thickness 0.15)
				)
				(justify left bottom)
				(hide yes)
			)
		)
		(property "Author" "Antmicro"
			(at 82.55 269.24 0)
			(effects
				(font
					(size 1.27 1.27)
					(thickness 0.15)
				)
				(justify left bottom)
				(hide yes)
			)
		)
		(property "License" "Apache-2.0"
			(at 82.55 271.78 0)
			(effects
				(font
					(size 1.27 1.27)
					(thickness 0.15)
				)
				(justify left bottom)
				(hide yes)
			)
		)
		(pin "3"
		)
		(pin "2"
		)
		(pin "1"
		)
		(instances
			(project "sodimm-ddr5-tester"
				(path ""
					(reference "Q9")
					(unit 1)
				)
			)
		)
	)
	(symbol
		(lib_id "antmicroCapacitors0402:C_100n_0402")
		(at 351.155 223.52 90)
		(unit 1)
		(exclude_from_sim no)
		(in_bom yes)
		(on_board yes)
		(dnp no)
		(fields_autoplaced yes)
		(property "Reference" "C9"
			(at 353.4791 220.143 90)
			(effects
				(font
					(size 1.27 1.27)
					(thickness 0.15)
				)
				(justify right)
			)
		)
		(property "Value" "C_100n_0402"
			(at 361.315 203.2 0)
			(effects
				(font
					(size 1.27 1.27)
					(thickness 0.15)
				)
				(justify left bottom)
				(hide yes)
			)
		)
		(property "Footprint" "antmicro-footprints:C_0402_1005Metric"
			(at 363.855 203.2 0)
			(effects
				(font
					(size 1.27 1.27)
					(thickness 0.15)
				)
				(justify left bottom)
				(hide yes)
			)
		)
		(property "Datasheet" "https://www.murata.com/products/productdetail?partno=GRM155R61H104KE14%23"
			(at 366.395 203.2 0)
			(effects
				(font
					(size 1.27 1.27)
					(thickness 0.15)
				)
				(justify left bottom)
				(hide yes)
			)
		)
		(property "Description" ""
			(at 351.155 223.52 0)
			(effects
				(font
					(size 1.27 1.27)
				)
			)
		)
		(property "MPN" "GRM155R61H104KE14D"
			(at 368.935 203.2 0)
			(effects
				(font
					(size 1.27 1.27)
					(thickness 0.15)
				)
				(justify left bottom)
				(hide yes)
			)
		)
		(property "Manufacturer" "Murata"
			(at 371.475 203.2 0)
			(effects
				(font
					(size 1.27 1.27)
					(thickness 0.15)
				)
				(justify left bottom)
				(hide yes)
			)
		)
		(property "License" "Apache-2.0"
			(at 374.015 203.2 0)
			(effects
				(font
					(size 1.27 1.27)
					(thickness 0.15)
				)
				(justify left bottom)
				(hide yes)
			)
		)
		(property "Author" "Antmicro"
			(at 376.555 203.2 0)
			(effects
				(font
					(size 1.27 1.27)
					(thickness 0.15)
				)
				(justify left bottom)
				(hide yes)
			)
		)
		(property "Val" "100n"
			(at 353.4791 222.6667 90)
			(effects
				(font
					(size 1.27 1.27)
					(thickness 0.15)
				)
				(justify right)
			)
		)
		(property "Voltage" "50V"
			(at 379.095 203.2 0)
			(effects
				(font
					(size 1.27 1.27)
				)
				(justify left bottom)
				(hide yes)
			)
		)
		(property "Dielectric" "X5R"
			(at 381.635 203.2 0)
			(effects
				(font
					(size 1.27 1.27)
				)
				(justify left bottom)
				(hide yes)
			)
		)
		(pin "1"
		)
		(pin "2"
		)
		(instances
			(project "sodimm-ddr5-tester"
				(path ""
					(reference "C9")
					(unit 1)
				)
			)
		)
	)
	(symbol
		(lib_id "antmicroResistors0402:R_0R_0402")
		(at 271.78 134.62 90)
		(unit 1)
		(exclude_from_sim no)
		(in_bom no)
		(on_board yes)
		(dnp yes)
		(property "Reference" "R26"
			(at 273.431 129.9835 90)
			(effects
				(font
					(size 1.27 1.27)
					(thickness 0.15)
				)
				(justify right)
			)
		)
		(property "Value" "R_0R_0402"
			(at 284.48 114.3 0)
			(effects
				(font
					(size 1.27 1.27)
					(thickness 0.15)
				)
				(justify left bottom)
				(hide yes)
			)
		)
		(property "Footprint" "antmicro-footprints:R_0402_1005Metric"
			(at 287.02 114.3 0)
			(effects
				(font
					(size 1.27 1.27)
					(thickness 0.15)
				)
				(justify left bottom)
				(hide yes)
			)
		)
		(property "Datasheet" "https://industrial.panasonic.com/cdbs/www-data/pdf/RDA0000/AOA0000C301.pdf"
			(at 289.56 114.3 0)
			(effects
				(font
					(size 1.27 1.27)
					(thickness 0.15)
				)
				(justify left bottom)
				(hide yes)
			)
		)
		(property "Description" ""
			(at 271.78 134.62 0)
			(effects
				(font
					(size 1.27 1.27)
				)
			)
		)
		(property "MPN" "ERJ2GE0R00X"
			(at 292.1 114.3 0)
			(effects
				(font
					(size 1.27 1.27)
					(thickness 0.15)
				)
				(justify left bottom)
				(hide yes)
			)
		)
		(property "Manufacturer" "Panasonic"
			(at 294.64 114.3 0)
			(effects
				(font
					(size 1.27 1.27)
					(thickness 0.15)
				)
				(justify left bottom)
				(hide yes)
			)
		)
		(property "License" "Apache-2.0"
			(at 297.18 114.3 0)
			(effects
				(font
					(size 1.27 1.27)
					(thickness 0.15)
				)
				(justify left bottom)
				(hide yes)
			)
		)
		(property "Author" "Antmicro"
			(at 299.72 114.3 0)
			(effects
				(font
					(size 1.27 1.27)
					(thickness 0.15)
				)
				(justify left bottom)
				(hide yes)
			)
		)
		(property "Val" "0R"
			(at 273.431 132.5072 90)
			(effects
				(font
					(size 1.27 1.27)
					(thickness 0.15)
				)
				(justify right)
			)
		)
		(property "Tolerance" "~"
			(at 281.94 114.3 0)
			(effects
				(font
					(size 1.27 1.27)
				)
				(justify left bottom)
				(hide yes)
			)
		)
		(property "Current" "1A"
			(at 302.26 114.3 0)
			(effects
				(font
					(size 1.27 1.27)
					(thickness 0.15)
				)
				(justify left bottom)
				(hide yes)
			)
		)
		(pin "1"
		)
		(pin "2"
		)
		(instances
			(project "sodimm-ddr5-tester"
				(path ""
					(reference "R26")
					(unit 1)
				)
			)
		)
	)
	(symbol
		(lib_id "antmicroResistors0402:R_47k_0402")
		(at 266.065 116.205 90)
		(unit 1)
		(exclude_from_sim no)
		(in_bom yes)
		(on_board yes)
		(dnp no)
		(fields_autoplaced yes)
		(property "Reference" "R23"
			(at 264.4141 112.8344 90)
			(effects
				(font
					(size 1.27 1.27)
					(thickness 0.15)
				)
				(justify left)
			)
		)
		(property "Value" "R_47k_0402"
			(at 278.765 95.885 0)
			(effects
				(font
					(size 1.27 1.27)
					(thickness 0.15)
				)
				(justify left bottom)
				(hide yes)
			)
		)
		(property "Footprint" "antmicro-footprints:R_0402_1005Metric"
			(at 281.305 95.885 0)
			(effects
				(font
					(size 1.27 1.27)
					(thickness 0.15)
				)
				(justify left bottom)
				(hide yes)
			)
		)
		(property "Datasheet" "https://www.bourns.com/docs/product-datasheets/cr.pdf"
			(at 283.845 95.885 0)
			(effects
				(font
					(size 1.27 1.27)
					(thickness 0.15)
				)
				(justify left bottom)
				(hide yes)
			)
		)
		(property "Description" ""
			(at 266.065 116.205 0)
			(effects
				(font
					(size 1.27 1.27)
				)
			)
		)
		(property "MPN" "CR0402-FX-4702GLF"
			(at 286.385 95.885 0)
			(effects
				(font
					(size 1.27 1.27)
					(thickness 0.15)
				)
				(justify left bottom)
				(hide yes)
			)
		)
		(property "Manufacturer" "Bourns"
			(at 288.925 95.885 0)
			(effects
				(font
					(size 1.27 1.27)
					(thickness 0.15)
				)
				(justify left bottom)
				(hide yes)
			)
		)
		(property "License" "Apache-2.0"
			(at 291.465 95.885 0)
			(effects
				(font
					(size 1.27 1.27)
					(thickness 0.15)
				)
				(justify left bottom)
				(hide yes)
			)
		)
		(property "Author" "Antmicro"
			(at 294.005 95.885 0)
			(effects
				(font
					(size 1.27 1.27)
					(thickness 0.15)
				)
				(justify left bottom)
				(hide yes)
			)
		)
		(property "Val" "47k"
			(at 264.4141 115.3581 90)
			(effects
				(font
					(size 1.27 1.27)
					(thickness 0.15)
				)
				(justify left)
			)
		)
		(property "Tolerance" "1%"
			(at 276.225 95.885 0)
			(effects
				(font
					(size 1.27 1.27)
				)
				(justify left bottom)
				(hide yes)
			)
		)
		(pin "1"
		)
		(pin "2"
		)
		(instances
			(project "sodimm-ddr5-tester"
				(path ""
					(reference "R23")
					(unit 1)
				)
			)
		)
	)
	(symbol
		(lib_id "antmicroResistors0402:R_0R_0402")
		(at 367.665 126.365 0)
		(unit 1)
		(exclude_from_sim no)
		(in_bom no)
		(on_board yes)
		(dnp yes)
		(property "Reference" "R35"
			(at 374.65 125.095 0)
			(effects
				(font
					(size 1.27 1.27)
					(thickness 0.15)
				)
			)
		)
		(property "Value" "R_0R_0402"
			(at 387.985 139.065 0)
			(effects
				(font
					(size 1.27 1.27)
					(thickness 0.15)
				)
				(justify left bottom)
				(hide yes)
			)
		)
		(property "Footprint" "antmicro-footprints:R_0402_1005Metric"
			(at 387.985 141.605 0)
			(effects
				(font
					(size 1.27 1.27)
					(thickness 0.15)
				)
				(justify left bottom)
				(hide yes)
			)
		)
		(property "Datasheet" "https://industrial.panasonic.com/cdbs/www-data/pdf/RDA0000/AOA0000C301.pdf"
			(at 387.985 144.145 0)
			(effects
				(font
					(size 1.27 1.27)
					(thickness 0.15)
				)
				(justify left bottom)
				(hide yes)
			)
		)
		(property "Description" ""
			(at 367.665 126.365 0)
			(effects
				(font
					(size 1.27 1.27)
				)
			)
		)
		(property "MPN" "ERJ2GE0R00X"
			(at 387.985 146.685 0)
			(effects
				(font
					(size 1.27 1.27)
					(thickness 0.15)
				)
				(justify left bottom)
				(hide yes)
			)
		)
		(property "Manufacturer" "Panasonic"
			(at 387.985 149.225 0)
			(effects
				(font
					(size 1.27 1.27)
					(thickness 0.15)
				)
				(justify left bottom)
				(hide yes)
			)
		)
		(property "License" "Apache-2.0"
			(at 387.985 151.765 0)
			(effects
				(font
					(size 1.27 1.27)
					(thickness 0.15)
				)
				(justify left bottom)
				(hide yes)
			)
		)
		(property "Author" "Antmicro"
			(at 387.985 154.305 0)
			(effects
				(font
					(size 1.27 1.27)
					(thickness 0.15)
				)
				(justify left bottom)
				(hide yes)
			)
		)
		(property "Val" "0R"
			(at 366.395 125.095 0)
			(effects
				(font
					(size 1.27 1.27)
					(thickness 0.15)
				)
			)
		)
		(property "Tolerance" "~"
			(at 387.985 136.525 0)
			(effects
				(font
					(size 1.27 1.27)
				)
				(justify left bottom)
				(hide yes)
			)
		)
		(property "Current" "1A"
			(at 387.985 156.845 0)
			(effects
				(font
					(size 1.27 1.27)
					(thickness 0.15)
				)
				(justify left bottom)
				(hide yes)
			)
		)
		(pin "1"
		)
		(pin "2"
		)
		(instances
			(project "sodimm-ddr5-tester"
				(path ""
					(reference "R35")
					(unit 1)
				)
			)
		)
	)
	(symbol
		(lib_id "antmicropower:+3V3")
		(at 266.065 107.315 0)
		(unit 1)
		(exclude_from_sim no)
		(in_bom yes)
		(on_board yes)
		(dnp no)
		(fields_autoplaced yes)
		(property "Reference" "#PWR032"
			(at 281.305 109.855 0)
			(effects
				(font
					(size 1.27 1.27)
					(thickness 0.15)
				)
				(justify left bottom)
				(hide yes)
			)
		)
		(property "Value" "+3V3"
			(at 262.89 104.775 0)
			(effects
				(font
					(size 1.27 1.27)
					(thickness 0.15)
				)
				(justify left bottom)
			)
		)
		(property "Footprint" ""
			(at 281.305 114.935 0)
			(effects
				(font
					(size 1.27 1.27)
					(thickness 0.15)
				)
				(justify left bottom)
				(hide yes)
			)
		)
		(property "Datasheet" ""
			(at 281.305 117.475 0)
			(effects
				(font
					(size 1.27 1.27)
					(thickness 0.15)
				)
				(justify left bottom)
				(hide yes)
			)
		)
		(property "Description" ""
			(at 266.065 107.315 0)
			(effects
				(font
					(size 1.27 1.27)
				)
			)
		)
		(property "Author" "Antmicro"
			(at 281.305 109.855 0)
			(effects
				(font
					(size 1.27 1.27)
					(thickness 0.15)
				)
				(justify left bottom)
				(hide yes)
			)
		)
		(property "License" "Apache-2.0"
			(at 281.305 112.395 0)
			(effects
				(font
					(size 1.27 1.27)
					(thickness 0.15)
				)
				(justify left bottom)
				(hide yes)
			)
		)
		(pin "1"
		)
		(instances
			(project "sodimm-ddr5-tester"
				(path ""
					(reference "#PWR032")
					(unit 1)
				)
			)
		)
	)
	(symbol
		(lib_id "antmicroResistors0402:R_330R_0402")
		(at 86.36 212.09 270)
		(unit 1)
		(exclude_from_sim no)
		(in_bom yes)
		(on_board yes)
		(dnp no)
		(fields_autoplaced yes)
		(property "Reference" "R62"
			(at 88.9 213.36 90)
			(effects
				(font
					(size 1.27 1.27)
				)
				(justify left)
			)
		)
		(property "Value" "R_330R_0402"
			(at 73.66 232.41 0)
			(effects
				(font
					(size 1.27 1.27)
					(thickness 0.15)
				)
				(justify left bottom)
				(hide yes)
			)
		)
		(property "Footprint" "antmicro-footprints:R_0402_1005Metric"
			(at 71.12 232.41 0)
			(effects
				(font
					(size 1.27 1.27)
					(thickness 0.15)
				)
				(justify left bottom)
				(hide yes)
			)
		)
		(property "Datasheet" "https://www.bourns.com/docs/product-datasheets/cr.pdf"
			(at 68.58 232.41 0)
			(effects
				(font
					(size 1.27 1.27)
					(thickness 0.15)
				)
				(justify left bottom)
				(hide yes)
			)
		)
		(property "Description" ""
			(at 86.36 212.09 0)
			(effects
				(font
					(size 1.27 1.27)
				)
			)
		)
		(property "Manufacturer" "Bourns"
			(at 63.5 232.41 0)
			(effects
				(font
					(size 1.27 1.27)
					(thickness 0.15)
				)
				(justify left bottom)
				(hide yes)
			)
		)
		(property "MPN" "CR0402-FX-3300GLF"
			(at 66.04 232.41 0)
			(effects
				(font
					(size 1.27 1.27)
					(thickness 0.15)
				)
				(justify left bottom)
				(hide yes)
			)
		)
		(property "Val" "330R"
			(at 88.9 216.5349 90)
			(effects
				(font
					(size 1.27 1.27)
					(thickness 0.15)
				)
				(justify left)
			)
		)
		(property "License" "Apache-2.0"
			(at 60.96 232.41 0)
			(effects
				(font
					(size 1.27 1.27)
					(thickness 0.15)
				)
				(justify left bottom)
				(hide yes)
			)
		)
		(property "Author" "Antmicro"
			(at 58.42 232.41 0)
			(effects
				(font
					(size 1.27 1.27)
					(thickness 0.15)
				)
				(justify left bottom)
				(hide yes)
			)
		)
		(property "Tolerance" "1%"
			(at 76.2 232.41 0)
			(effects
				(font
					(size 1.27 1.27)
				)
				(justify left bottom)
				(hide yes)
			)
		)
		(pin "1"
		)
		(pin "2"
		)
		(instances
			(project "sodimm-ddr5-tester"
				(path ""
					(reference "R62")
					(unit 1)
				)
			)
		)
	)
	(symbol
		(lib_id "antmicroResistors0402:R_0R_0402")
		(at 275.59 123.825 0)
		(unit 1)
		(exclude_from_sim no)
		(in_bom yes)
		(on_board yes)
		(dnp no)
		(property "Reference" "R28"
			(at 281.94 122.555 0)
			(effects
				(font
					(size 1.27 1.27)
					(thickness 0.15)
				)
			)
		)
		(property "Value" "R_0R_0402"
			(at 295.91 136.525 0)
			(effects
				(font
					(size 1.27 1.27)
					(thickness 0.15)
				)
				(justify left bottom)
				(hide yes)
			)
		)
		(property "Footprint" "antmicro-footprints:R_0402_1005Metric"
			(at 295.91 139.065 0)
			(effects
				(font
					(size 1.27 1.27)
					(thickness 0.15)
				)
				(justify left bottom)
				(hide yes)
			)
		)
		(property "Datasheet" "https://industrial.panasonic.com/cdbs/www-data/pdf/RDA0000/AOA0000C301.pdf"
			(at 295.91 141.605 0)
			(effects
				(font
					(size 1.27 1.27)
					(thickness 0.15)
				)
				(justify left bottom)
				(hide yes)
			)
		)
		(property "Description" ""
			(at 275.59 123.825 0)
			(effects
				(font
					(size 1.27 1.27)
				)
			)
		)
		(property "MPN" "ERJ2GE0R00X"
			(at 295.91 144.145 0)
			(effects
				(font
					(size 1.27 1.27)
					(thickness 0.15)
				)
				(justify left bottom)
				(hide yes)
			)
		)
		(property "Manufacturer" "Panasonic"
			(at 295.91 146.685 0)
			(effects
				(font
					(size 1.27 1.27)
					(thickness 0.15)
				)
				(justify left bottom)
				(hide yes)
			)
		)
		(property "License" "Apache-2.0"
			(at 295.91 149.225 0)
			(effects
				(font
					(size 1.27 1.27)
					(thickness 0.15)
				)
				(justify left bottom)
				(hide yes)
			)
		)
		(property "Author" "Antmicro"
			(at 295.91 151.765 0)
			(effects
				(font
					(size 1.27 1.27)
					(thickness 0.15)
				)
				(justify left bottom)
				(hide yes)
			)
		)
		(property "Val" "0R"
			(at 274.32 122.555 0)
			(effects
				(font
					(size 1.27 1.27)
					(thickness 0.15)
				)
			)
		)
		(property "Tolerance" "~"
			(at 295.91 133.985 0)
			(effects
				(font
					(size 1.27 1.27)
				)
				(justify left bottom)
				(hide yes)
			)
		)
		(property "Current" "1A"
			(at 295.91 154.305 0)
			(effects
				(font
					(size 1.27 1.27)
					(thickness 0.15)
				)
				(justify left bottom)
				(hide yes)
			)
		)
		(pin "1"
		)
		(pin "2"
		)
		(instances
			(project "sodimm-ddr5-tester"
				(path ""
					(reference "R28")
					(unit 1)
				)
			)
		)
	)
	(symbol
		(lib_id "antmicroResistors0402:R_330R_0402")
		(at 67.31 212.09 270)
		(unit 1)
		(exclude_from_sim no)
		(in_bom yes)
		(on_board yes)
		(dnp no)
		(fields_autoplaced yes)
		(property "Reference" "R61"
			(at 69.85 213.36 90)
			(effects
				(font
					(size 1.27 1.27)
				)
				(justify left)
			)
		)
		(property "Value" "R_330R_0402"
			(at 54.61 232.41 0)
			(effects
				(font
					(size 1.27 1.27)
					(thickness 0.15)
				)
				(justify left bottom)
				(hide yes)
			)
		)
		(property "Footprint" "antmicro-footprints:R_0402_1005Metric"
			(at 52.07 232.41 0)
			(effects
				(font
					(size 1.27 1.27)
					(thickness 0.15)
				)
				(justify left bottom)
				(hide yes)
			)
		)
		(property "Datasheet" "https://www.bourns.com/docs/product-datasheets/cr.pdf"
			(at 49.53 232.41 0)
			(effects
				(font
					(size 1.27 1.27)
					(thickness 0.15)
				)
				(justify left bottom)
				(hide yes)
			)
		)
		(property "Description" ""
			(at 67.31 212.09 0)
			(effects
				(font
					(size 1.27 1.27)
				)
			)
		)
		(property "Manufacturer" "Bourns"
			(at 44.45 232.41 0)
			(effects
				(font
					(size 1.27 1.27)
					(thickness 0.15)
				)
				(justify left bottom)
				(hide yes)
			)
		)
		(property "MPN" "CR0402-FX-3300GLF"
			(at 46.99 232.41 0)
			(effects
				(font
					(size 1.27 1.27)
					(thickness 0.15)
				)
				(justify left bottom)
				(hide yes)
			)
		)
		(property "Val" "330R"
			(at 69.85 216.5349 90)
			(effects
				(font
					(size 1.27 1.27)
					(thickness 0.15)
				)
				(justify left)
			)
		)
		(property "License" "Apache-2.0"
			(at 41.91 232.41 0)
			(effects
				(font
					(size 1.27 1.27)
					(thickness 0.15)
				)
				(justify left bottom)
				(hide yes)
			)
		)
		(property "Author" "Antmicro"
			(at 39.37 232.41 0)
			(effects
				(font
					(size 1.27 1.27)
					(thickness 0.15)
				)
				(justify left bottom)
				(hide yes)
			)
		)
		(property "Tolerance" "1%"
			(at 57.15 232.41 0)
			(effects
				(font
					(size 1.27 1.27)
				)
				(justify left bottom)
				(hide yes)
			)
		)
		(pin "1"
		)
		(pin "2"
		)
		(instances
			(project "sodimm-ddr5-tester"
				(path ""
					(reference "R61")
					(unit 1)
				)
			)
		)
	)
	(symbol
		(lib_id "antmicropower:GND")
		(at 67.31 251.46 0)
		(unit 1)
		(exclude_from_sim no)
		(in_bom yes)
		(on_board yes)
		(dnp no)
		(property "Reference" "#PWR0201"
			(at 67.31 257.81 0)
			(effects
				(font
					(size 1.27 1.27)
				)
				(hide yes)
			)
		)
		(property "Value" "GND"
			(at 65.532 255.524 0)
			(effects
				(font
					(size 1.27 1.27)
					(thickness 0.15)
				)
				(justify left)
			)
		)
		(property "Footprint" ""
			(at 76.2 259.08 0)
			(effects
				(font
					(size 1.27 1.27)
					(thickness 0.15)
				)
				(justify left bottom)
				(hide yes)
			)
		)
		(property "Datasheet" ""
			(at 76.2 264.16 0)
			(effects
				(font
					(size 1.27 1.27)
					(thickness 0.15)
				)
				(justify left bottom)
				(hide yes)
			)
		)
		(property "Description" ""
			(at 76.2 266.7 0)
			(effects
				(font
					(size 1.27 1.27)
				)
				(justify left bottom)
				(hide yes)
			)
		)
		(property "Author" "Antmicro"
			(at 76.2 259.08 0)
			(effects
				(font
					(size 1.27 1.27)
					(thickness 0.15)
				)
				(justify left bottom)
				(hide yes)
			)
		)
		(property "License" "Apache-2.0"
			(at 76.2 261.62 0)
			(effects
				(font
					(size 1.27 1.27)
					(thickness 0.15)
				)
				(justify left bottom)
				(hide yes)
			)
		)
		(pin "1"
		)
		(instances
			(project "sodimm-ddr5-tester"
				(path ""
					(reference "#PWR0201")
					(unit 1)
				)
			)
		)
	)
	(symbol
		(lib_id "antmicroResistors0402:R_0R_0402")
		(at 367.665 121.92 0)
		(unit 1)
		(exclude_from_sim no)
		(in_bom no)
		(on_board yes)
		(dnp yes)
		(property "Reference" "R34"
			(at 374.65 120.65 0)
			(effects
				(font
					(size 1.27 1.27)
					(thickness 0.15)
				)
			)
		)
		(property "Value" "R_0R_0402"
			(at 387.985 134.62 0)
			(effects
				(font
					(size 1.27 1.27)
					(thickness 0.15)
				)
				(justify left bottom)
				(hide yes)
			)
		)
		(property "Footprint" "antmicro-footprints:R_0402_1005Metric"
			(at 387.985 137.16 0)
			(effects
				(font
					(size 1.27 1.27)
					(thickness 0.15)
				)
				(justify left bottom)
				(hide yes)
			)
		)
		(property "Datasheet" "https://industrial.panasonic.com/cdbs/www-data/pdf/RDA0000/AOA0000C301.pdf"
			(at 387.985 139.7 0)
			(effects
				(font
					(size 1.27 1.27)
					(thickness 0.15)
				)
				(justify left bottom)
				(hide yes)
			)
		)
		(property "Description" ""
			(at 367.665 121.92 0)
			(effects
				(font
					(size 1.27 1.27)
				)
			)
		)
		(property "MPN" "ERJ2GE0R00X"
			(at 387.985 142.24 0)
			(effects
				(font
					(size 1.27 1.27)
					(thickness 0.15)
				)
				(justify left bottom)
				(hide yes)
			)
		)
		(property "Manufacturer" "Panasonic"
			(at 387.985 144.78 0)
			(effects
				(font
					(size 1.27 1.27)
					(thickness 0.15)
				)
				(justify left bottom)
				(hide yes)
			)
		)
		(property "License" "Apache-2.0"
			(at 387.985 147.32 0)
			(effects
				(font
					(size 1.27 1.27)
					(thickness 0.15)
				)
				(justify left bottom)
				(hide yes)
			)
		)
		(property "Author" "Antmicro"
			(at 387.985 149.86 0)
			(effects
				(font
					(size 1.27 1.27)
					(thickness 0.15)
				)
				(justify left bottom)
				(hide yes)
			)
		)
		(property "Val" "0R"
			(at 366.395 120.65 0)
			(effects
				(font
					(size 1.27 1.27)
					(thickness 0.15)
				)
			)
		)
		(property "Tolerance" "~"
			(at 387.985 132.08 0)
			(effects
				(font
					(size 1.27 1.27)
				)
				(justify left bottom)
				(hide yes)
			)
		)
		(property "Current" "1A"
			(at 387.985 152.4 0)
			(effects
				(font
					(size 1.27 1.27)
					(thickness 0.15)
				)
				(justify left bottom)
				(hide yes)
			)
		)
		(pin "1"
		)
		(pin "2"
		)
		(instances
			(project "sodimm-ddr5-tester"
				(path ""
					(reference "R34")
					(unit 1)
				)
			)
		)
	)
	(symbol
		(lib_id "antmicroTransistorsFETsMOSFETsSingle:BSS138PW,115")
		(at 96.52 227.33 0)
		(unit 1)
		(exclude_from_sim no)
		(in_bom yes)
		(on_board yes)
		(dnp no)
		(property "Reference" "Q11"
			(at 106.68 223.52 0)
			(effects
				(font
					(size 1.27 1.27)
					(thickness 0.15)
				)
				(justify left)
			)
		)
		(property "Value" "BSS138PW,115"
			(at 119.38 236.22 0)
			(effects
				(font
					(size 1.27 1.27)
					(thickness 0.15)
				)
				(justify left bottom)
				(hide yes)
			)
		)
		(property "Footprint" "antmicro-footprints:SC70-3"
			(at 119.38 238.76 0)
			(effects
				(font
					(size 1.27 1.27)
					(thickness 0.15)
				)
				(justify left bottom)
				(hide yes)
			)
		)
		(property "Datasheet" "https://assets.nexperia.com/documents/data-sheet/BSS138PW.pdf"
			(at 119.38 241.3 0)
			(effects
				(font
					(size 1.27 1.27)
					(thickness 0.15)
				)
				(justify left bottom)
				(hide yes)
			)
		)
		(property "Description" "Power MOSFET, N Channel, 60 V, 320 mA, 0.9 ohm, SOT-323, Surface Mount"
			(at 119.38 254 0)
			(effects
				(font
					(size 1.27 1.27)
				)
				(justify left bottom)
				(hide yes)
			)
		)
		(property "MPN" "BSS138PW,115"
			(at 106.68 226.06 0)
			(effects
				(font
					(size 1.27 1.27)
					(thickness 0.15)
				)
				(justify left)
			)
		)
		(property "Manufacturer" "Nexperia"
			(at 119.38 246.38 0)
			(effects
				(font
					(size 1.27 1.27)
					(thickness 0.15)
				)
				(justify left bottom)
				(hide yes)
			)
		)
		(property "Author" "Antmicro"
			(at 119.38 248.92 0)
			(effects
				(font
					(size 1.27 1.27)
					(thickness 0.15)
				)
				(justify left bottom)
				(hide yes)
			)
		)
		(property "License" "Apache-2.0"
			(at 119.38 251.46 0)
			(effects
				(font
					(size 1.27 1.27)
					(thickness 0.15)
				)
				(justify left bottom)
				(hide yes)
			)
		)
		(pin "3"
		)
		(pin "2"
		)
		(pin "1"
		)
		(instances
			(project "sodimm-ddr5-tester"
				(path ""
					(reference "Q11")
					(unit 1)
				)
			)
		)
	)
	(symbol
		(lib_id "antmicroMemoryConnectorsPCCardSockets:Bus_DDR5_SODIMM_Amphenol_10161033-002RHLF_CUSTOM_2xDetectPin")
		(at 167.64 46.99 0)
		(unit 2)
		(exclude_from_sim no)
		(in_bom yes)
		(on_board yes)
		(dnp no)
		(fields_autoplaced yes)
		(property "Reference" "J2"
			(at 185.42 40.765 0)
			(effects
				(font
					(size 1.27 1.27)
					(thickness 0.15)
				)
			)
		)
		(property "Value" "Bus_DDR5_SODIMM_Amphenol_10161033-002RHLF_CUSTOM_2xDetectPin"
			(at 218.44 54.61 0)
			(effects
				(font
					(size 1.27 1.27)
					(thickness 0.15)
				)
				(justify left bottom)
				(hide yes)
			)
		)
		(property "Footprint" "antmicro-footprints:Bus_DDR5_SODIMM_Amphenol_10161033-002RHLF"
			(at 218.44 57.15 0)
			(effects
				(font
					(size 1.27 1.27)
					(thickness 0.15)
				)
				(justify left bottom)
				(hide yes)
			)
		)
		(property "Datasheet" "https://cdn.amphenol-cs.com/media/wysiwyg/files/documentation/datasheet/ssio/ssio_ddr5_sodimm.pdf"
			(at 218.44 59.69 0)
			(effects
				(font
					(size 1.27 1.27)
					(thickness 0.15)
				)
				(justify left bottom)
				(hide yes)
			)
		)
		(property "Description" ""
			(at 167.64 46.99 0)
			(effects
				(font
					(size 1.27 1.27)
				)
			)
		)
		(property "MPN" "10161033-002RHLF"
			(at 185.42 43.2887 0)
			(effects
				(font
					(size 1.27 1.27)
					(thickness 0.15)
				)
			)
		)
		(property "Manufacturer" "Amphenol"
			(at 218.44 62.23 0)
			(effects
				(font
					(size 1.27 1.27)
					(thickness 0.15)
				)
				(justify left bottom)
				(hide yes)
			)
		)
		(property "Author" "Antmicro"
			(at 218.44 64.77 0)
			(effects
				(font
					(size 1.27 1.27)
					(thickness 0.15)
				)
				(justify left bottom)
				(hide yes)
			)
		)
		(property "License" "Apache-2.0"
			(at 218.44 67.31 0)
			(effects
				(font
					(size 1.27 1.27)
					(thickness 0.15)
				)
				(justify left bottom)
				(hide yes)
			)
		)
		(pin "100"
		)
		(pin "102"
		)
		(pin "103"
		)
		(pin "106"
		)
		(pin "107"
		)
		(pin "109"
		)
		(pin "11"
		)
		(pin "110"
		)
		(pin "113"
		)
		(pin "114"
		)
		(pin "115"
		)
		(pin "116"
		)
		(pin "119"
		)
		(pin "12"
		)
		(pin "120"
		)
		(pin "121"
		)
		(pin "122"
		)
		(pin "125"
		)
		(pin "126"
		)
		(pin "127"
		)
		(pin "131"
		)
		(pin "132"
		)
		(pin "133"
		)
		(pin "134"
		)
		(pin "15"
		)
		(pin "16"
		)
		(pin "19"
		)
		(pin "20"
		)
		(pin "22"
		)
		(pin "23"
		)
		(pin "26"
		)
		(pin "27"
		)
		(pin "30"
		)
		(pin "31"
		)
		(pin "34"
		)
		(pin "35"
		)
		(pin "38"
		)
		(pin "39"
		)
		(pin "41"
		)
		(pin "42"
		)
		(pin "45"
		)
		(pin "46"
		)
		(pin "49"
		)
		(pin "50"
		)
		(pin "53"
		)
		(pin "54"
		)
		(pin "57"
		)
		(pin "58"
		)
		(pin "61"
		)
		(pin "62"
		)
		(pin "64"
		)
		(pin "65"
		)
		(pin "68"
		)
		(pin "69"
		)
		(pin "72"
		)
		(pin "73"
		)
		(pin "76"
		)
		(pin "77"
		)
		(pin "80"
		)
		(pin "81"
		)
		(pin "83"
		)
		(pin "84"
		)
		(pin "87"
		)
		(pin "88"
		)
		(pin "91"
		)
		(pin "92"
		)
		(pin "95"
		)
		(pin "96"
		)
		(pin "99"
		)
		(pin "137"
		)
		(pin "138"
		)
		(pin "139"
		)
		(pin "140"
		)
		(pin "144"
		)
		(pin "145"
		)
		(pin "146"
		)
		(pin "149"
		)
		(pin "150"
		)
		(pin "151"
		)
		(pin "152"
		)
		(pin "155"
		)
		(pin "156"
		)
		(pin "157"
		)
		(pin "158"
		)
		(pin "161"
		)
		(pin "162"
		)
		(pin "164"
		)
		(pin "165"
		)
		(pin "168"
		)
		(pin "169"
		)
		(pin "171"
		)
		(pin "172"
		)
		(pin "175"
		)
		(pin "176"
		)
		(pin "179"
		)
		(pin "180"
		)
		(pin "183"
		)
		(pin "184"
		)
		(pin "187"
		)
		(pin "188"
		)
		(pin "190"
		)
		(pin "191"
		)
		(pin "194"
		)
		(pin "195"
		)
		(pin "198"
		)
		(pin "199"
		)
		(pin "202"
		)
		(pin "203"
		)
		(pin "206"
		)
		(pin "207"
		)
		(pin "209"
		)
		(pin "210"
		)
		(pin "213"
		)
		(pin "214"
		)
		(pin "217"
		)
		(pin "218"
		)
		(pin "221"
		)
		(pin "222"
		)
		(pin "225"
		)
		(pin "226"
		)
		(pin "229"
		)
		(pin "230"
		)
		(pin "232"
		)
		(pin "233"
		)
		(pin "236"
		)
		(pin "237"
		)
		(pin "240"
		)
		(pin "241"
		)
		(pin "244"
		)
		(pin "245"
		)
		(pin "248"
		)
		(pin "249"
		)
		(pin "251"
		)
		(pin "252"
		)
		(pin "255"
		)
		(pin "256"
		)
		(pin "259"
		)
		(pin "260"
		)
		(pin "1"
		)
		(pin "10"
		)
		(pin "101"
		)
		(pin "104"
		)
		(pin "105"
		)
		(pin "108"
		)
		(pin "111"
		)
		(pin "112"
		)
		(pin "117"
		)
		(pin "118"
		)
		(pin "123"
		)
		(pin "124"
		)
		(pin "128"
		)
		(pin "129"
		)
		(pin "13"
		)
		(pin "130"
		)
		(pin "135"
		)
		(pin "136"
		)
		(pin "14"
		)
		(pin "141"
		)
		(pin "142"
		)
		(pin "143"
		)
		(pin "147"
		)
		(pin "148"
		)
		(pin "153"
		)
		(pin "154"
		)
		(pin "159"
		)
		(pin "160"
		)
		(pin "163"
		)
		(pin "166"
		)
		(pin "167"
		)
		(pin "17"
		)
		(pin "170"
		)
		(pin "173"
		)
		(pin "174"
		)
		(pin "177"
		)
		(pin "178"
		)
		(pin "18"
		)
		(pin "181"
		)
		(pin "182"
		)
		(pin "185"
		)
		(pin "186"
		)
		(pin "189"
		)
		(pin "192"
		)
		(pin "193"
		)
		(pin "196"
		)
		(pin "197"
		)
		(pin "2"
		)
		(pin "200"
		)
		(pin "201"
		)
		(pin "204"
		)
		(pin "205"
		)
		(pin "208"
		)
		(pin "21"
		)
		(pin "211"
		)
		(pin "212"
		)
		(pin "215"
		)
		(pin "216"
		)
		(pin "219"
		)
		(pin "220"
		)
		(pin "223"
		)
		(pin "224"
		)
		(pin "227"
		)
		(pin "228"
		)
		(pin "231"
		)
		(pin "234"
		)
		(pin "235"
		)
		(pin "238"
		)
		(pin "239"
		)
		(pin "24"
		)
		(pin "242"
		)
		(pin "243"
		)
		(pin "246"
		)
		(pin "247"
		)
		(pin "25"
		)
		(pin "250"
		)
		(pin "253"
		)
		(pin "254"
		)
		(pin "257"
		)
		(pin "258"
		)
		(pin "261"
		)
		(pin "262"
		)
		(pin "28"
		)
		(pin "29"
		)
		(pin "3"
		)
		(pin "32"
		)
		(pin "33"
		)
		(pin "36"
		)
		(pin "37"
		)
		(pin "4"
		)
		(pin "40"
		)
		(pin "43"
		)
		(pin "44"
		)
		(pin "47"
		)
		(pin "48"
		)
		(pin "5"
		)
		(pin "51"
		)
		(pin "52"
		)
		(pin "55"
		)
		(pin "56"
		)
		(pin "59"
		)
		(pin "6"
		)
		(pin "60"
		)
		(pin "63"
		)
		(pin "66"
		)
		(pin "67"
		)
		(pin "7"
		)
		(pin "70"
		)
		(pin "71"
		)
		(pin "74"
		)
		(pin "75"
		)
		(pin "78"
		)
		(pin "79"
		)
		(pin "8"
		)
		(pin "82"
		)
		(pin "85"
		)
		(pin "86"
		)
		(pin "89"
		)
		(pin "9"
		)
		(pin "90"
		)
		(pin "93"
		)
		(pin "94"
		)
		(pin "97"
		)
		(pin "98"
		)
		(pin "SH"
		)
		(instances
			(project "sodimm-ddr5-tester"
				(path ""
					(reference "J2")
					(unit 2)
				)
			)
		)
	)
	(symbol
		(lib_id "antmicropower:GND")
		(at 364.49 138.43 0)
		(unit 1)
		(exclude_from_sim no)
		(in_bom yes)
		(on_board yes)
		(dnp no)
		(property "Reference" "#PWR040"
			(at 364.49 144.78 0)
			(effects
				(font
					(size 1.27 1.27)
				)
				(hide yes)
			)
		)
		(property "Value" "GND"
			(at 362.712 142.748 0)
			(effects
				(font
					(size 1.27 1.27)
					(thickness 0.15)
				)
				(justify left)
			)
		)
		(property "Footprint" ""
			(at 373.38 146.05 0)
			(effects
				(font
					(size 1.27 1.27)
					(thickness 0.15)
				)
				(justify left bottom)
				(hide yes)
			)
		)
		(property "Datasheet" ""
			(at 373.38 151.13 0)
			(effects
				(font
					(size 1.27 1.27)
					(thickness 0.15)
				)
				(justify left bottom)
				(hide yes)
			)
		)
		(property "Description" ""
			(at 373.38 153.67 0)
			(effects
				(font
					(size 1.27 1.27)
				)
				(justify left bottom)
				(hide yes)
			)
		)
		(property "Author" "Antmicro"
			(at 373.38 146.05 0)
			(effects
				(font
					(size 1.27 1.27)
					(thickness 0.15)
				)
				(justify left bottom)
				(hide yes)
			)
		)
		(property "License" "Apache-2.0"
			(at 373.38 148.59 0)
			(effects
				(font
					(size 1.27 1.27)
					(thickness 0.15)
				)
				(justify left bottom)
				(hide yes)
			)
		)
		(pin "1"
		)
		(instances
			(project "sodimm-ddr5-tester"
				(path ""
					(reference "#PWR040")
					(unit 1)
				)
			)
		)
	)
	(symbol
		(lib_id "antmicropower:GND")
		(at 266.065 136.525 0)
		(unit 1)
		(exclude_from_sim no)
		(in_bom yes)
		(on_board yes)
		(dnp no)
		(property "Reference" "#PWR033"
			(at 266.065 142.875 0)
			(effects
				(font
					(size 1.27 1.27)
				)
				(hide yes)
			)
		)
		(property "Value" "GND"
			(at 263.652 140.716 0)
			(effects
				(font
					(size 1.27 1.27)
					(thickness 0.15)
				)
				(justify left)
			)
		)
		(property "Footprint" ""
			(at 274.955 144.145 0)
			(effects
				(font
					(size 1.27 1.27)
					(thickness 0.15)
				)
				(justify left bottom)
				(hide yes)
			)
		)
		(property "Datasheet" ""
			(at 274.955 149.225 0)
			(effects
				(font
					(size 1.27 1.27)
					(thickness 0.15)
				)
				(justify left bottom)
				(hide yes)
			)
		)
		(property "Description" ""
			(at 274.955 151.765 0)
			(effects
				(font
					(size 1.27 1.27)
				)
				(justify left bottom)
				(hide yes)
			)
		)
		(property "Author" "Antmicro"
			(at 274.955 144.145 0)
			(effects
				(font
					(size 1.27 1.27)
					(thickness 0.15)
				)
				(justify left bottom)
				(hide yes)
			)
		)
		(property "License" "Apache-2.0"
			(at 274.955 146.685 0)
			(effects
				(font
					(size 1.27 1.27)
					(thickness 0.15)
				)
				(justify left bottom)
				(hide yes)
			)
		)
		(pin "1"
		)
		(instances
			(project "sodimm-ddr5-tester"
				(path ""
					(reference "#PWR033")
					(unit 1)
				)
			)
		)
	)
	(symbol
		(lib_id "antmicropower:GND")
		(at 86.36 251.46 0)
		(unit 1)
		(exclude_from_sim no)
		(in_bom yes)
		(on_board yes)
		(dnp no)
		(property "Reference" "#PWR0203"
			(at 86.36 257.81 0)
			(effects
				(font
					(size 1.27 1.27)
				)
				(hide yes)
			)
		)
		(property "Value" "GND"
			(at 84.582 255.524 0)
			(effects
				(font
					(size 1.27 1.27)
					(thickness 0.15)
				)
				(justify left)
			)
		)
		(property "Footprint" ""
			(at 95.25 259.08 0)
			(effects
				(font
					(size 1.27 1.27)
					(thickness 0.15)
				)
				(justify left bottom)
				(hide yes)
			)
		)
		(property "Datasheet" ""
			(at 95.25 264.16 0)
			(effects
				(font
					(size 1.27 1.27)
					(thickness 0.15)
				)
				(justify left bottom)
				(hide yes)
			)
		)
		(property "Description" ""
			(at 95.25 266.7 0)
			(effects
				(font
					(size 1.27 1.27)
				)
				(justify left bottom)
				(hide yes)
			)
		)
		(property "Author" "Antmicro"
			(at 95.25 259.08 0)
			(effects
				(font
					(size 1.27 1.27)
					(thickness 0.15)
				)
				(justify left bottom)
				(hide yes)
			)
		)
		(property "License" "Apache-2.0"
			(at 95.25 261.62 0)
			(effects
				(font
					(size 1.27 1.27)
					(thickness 0.15)
				)
				(justify left bottom)
				(hide yes)
			)
		)
		(pin "1"
		)
		(instances
			(project "sodimm-ddr5-tester"
				(path ""
					(reference "#PWR0203")
					(unit 1)
				)
			)
		)
	)
	(symbol
		(lib_id "antmicroCapacitors0402:C_100n_0402")
		(at 267.97 59.69 90)
		(unit 1)
		(exclude_from_sim no)
		(in_bom yes)
		(on_board yes)
		(dnp no)
		(fields_autoplaced yes)
		(property "Reference" "C6"
			(at 271.145 55.8735 90)
			(effects
				(font
					(size 1.27 1.27)
					(thickness 0.15)
				)
				(justify right)
			)
		)
		(property "Value" "C_100n_0402"
			(at 278.13 39.37 0)
			(effects
				(font
					(size 1.27 1.27)
					(thickness 0.15)
				)
				(justify left bottom)
				(hide yes)
			)
		)
		(property "Footprint" "antmicro-footprints:C_0402_1005Metric"
			(at 280.67 39.37 0)
			(effects
				(font
					(size 1.27 1.27)
					(thickness 0.15)
				)
				(justify left bottom)
				(hide yes)
			)
		)
		(property "Datasheet" "https://www.murata.com/products/productdetail?partno=GRM155R61H104KE14%23"
			(at 283.21 39.37 0)
			(effects
				(font
					(size 1.27 1.27)
					(thickness 0.15)
				)
				(justify left bottom)
				(hide yes)
			)
		)
		(property "Description" ""
			(at 267.97 59.69 0)
			(effects
				(font
					(size 1.27 1.27)
				)
			)
		)
		(property "MPN" "GRM155R61H104KE14D"
			(at 285.75 39.37 0)
			(effects
				(font
					(size 1.27 1.27)
					(thickness 0.15)
				)
				(justify left bottom)
				(hide yes)
			)
		)
		(property "Manufacturer" "Murata"
			(at 288.29 39.37 0)
			(effects
				(font
					(size 1.27 1.27)
					(thickness 0.15)
				)
				(justify left bottom)
				(hide yes)
			)
		)
		(property "License" "Apache-2.0"
			(at 290.83 39.37 0)
			(effects
				(font
					(size 1.27 1.27)
					(thickness 0.15)
				)
				(justify left bottom)
				(hide yes)
			)
		)
		(property "Author" "Antmicro"
			(at 293.37 39.37 0)
			(effects
				(font
					(size 1.27 1.27)
					(thickness 0.15)
				)
				(justify left bottom)
				(hide yes)
			)
		)
		(property "Val" "100n"
			(at 271.145 58.4135 90)
			(effects
				(font
					(size 1.27 1.27)
					(thickness 0.15)
				)
				(justify right)
			)
		)
		(property "Voltage" "50V"
			(at 295.91 39.37 0)
			(effects
				(font
					(size 1.27 1.27)
				)
				(justify left bottom)
				(hide yes)
			)
		)
		(property "Dielectric" "X5R"
			(at 298.45 39.37 0)
			(effects
				(font
					(size 1.27 1.27)
				)
				(justify left bottom)
				(hide yes)
			)
		)
		(pin "1"
		)
		(pin "2"
		)
		(instances
			(project "sodimm-ddr5-tester"
				(path ""
					(reference "C6")
					(unit 1)
				)
			)
		)
	)
	(symbol
		(lib_id "antmicroLEDIndicationDiscrete:LED_RGY_0606_APTF1616SURKCGKSYKC")
		(at 41.91 203.2 0)
		(unit 1)
		(exclude_from_sim no)
		(in_bom yes)
		(on_board yes)
		(dnp no)
		(fields_autoplaced yes)
		(property "Reference" "D9"
			(at 51.435 195.58 0)
			(effects
				(font
					(size 1.27 1.27)
				)
			)
		)
		(property "Value" "LED_RGY_0606_APTF1616SURKCGKSYKC"
			(at 51.435 198.12 0)
			(effects
				(font
					(size 1.27 1.27)
					(thickness 0.15)
				)
			)
		)
		(property "Footprint" "antmicro-footprints:LED_RGY_1.6x1.6mm_APTF1616"
			(at 74.93 212.09 0)
			(effects
				(font
					(size 1.27 1.27)
					(thickness 0.15)
				)
				(justify left bottom)
				(hide yes)
			)
		)
		(property "Datasheet" "http://www.mouser.com/datasheet/2/216/APTF1616SURKCGKSYKC-1145193.pdf"
			(at 74.93 214.63 0)
			(effects
				(font
					(size 1.27 1.27)
					(thickness 0.15)
				)
				(justify left bottom)
				(hide yes)
			)
		)
		(property "Description" "Standard LEDs - SMD RGY 1616 SMD"
			(at 74.93 217.17 0)
			(effects
				(font
					(size 1.27 1.27)
					(thickness 0.15)
				)
				(justify left bottom)
				(hide yes)
			)
		)
		(property "MPN" "APTF1616SURKCGKSYKC"
			(at 74.93 219.71 0)
			(effects
				(font
					(size 1.27 1.27)
					(thickness 0.15)
				)
				(justify left bottom)
				(hide yes)
			)
		)
		(property "Manufacturer" "Kingbright"
			(at 74.93 222.25 0)
			(effects
				(font
					(size 1.27 1.27)
					(thickness 0.15)
				)
				(justify left bottom)
				(hide yes)
			)
		)
		(property "Author" "Antmicro"
			(at 74.93 224.79 0)
			(effects
				(font
					(size 1.27 1.27)
					(thickness 0.15)
				)
				(justify left bottom)
				(hide yes)
			)
		)
		(property "License" "Apache-2.0"
			(at 74.93 227.33 0)
			(effects
				(font
					(size 1.27 1.27)
					(thickness 0.15)
				)
				(justify left bottom)
				(hide yes)
			)
		)
		(pin "1"
		)
		(pin "2"
		)
		(pin "3"
		)
		(pin "4"
		)
		(instances
			(project "sodimm-ddr5-tester"
				(path ""
					(reference "D9")
					(unit 1)
				)
			)
		)
	)
	(symbol
		(lib_id "antmicroResistors0402:R_0R_0402")
		(at 359.41 136.525 90)
		(unit 1)
		(exclude_from_sim no)
		(in_bom no)
		(on_board yes)
		(dnp yes)
		(fields_autoplaced yes)
		(property "Reference" "R30"
			(at 358.14 137.795 0)
			(effects
				(font
					(size 1.27 1.27)
					(thickness 0.15)
				)
			)
		)
		(property "Value" "R_0R_0402"
			(at 372.11 116.205 0)
			(effects
				(font
					(size 1.27 1.27)
					(thickness 0.15)
				)
				(justify left bottom)
				(hide yes)
			)
		)
		(property "Footprint" "antmicro-footprints:R_0402_1005Metric"
			(at 374.65 116.205 0)
			(effects
				(font
					(size 1.27 1.27)
					(thickness 0.15)
				)
				(justify left bottom)
				(hide yes)
			)
		)
		(property "Datasheet" "https://industrial.panasonic.com/cdbs/www-data/pdf/RDA0000/AOA0000C301.pdf"
			(at 377.19 116.205 0)
			(effects
				(font
					(size 1.27 1.27)
					(thickness 0.15)
				)
				(justify left bottom)
				(hide yes)
			)
		)
		(property "Description" ""
			(at 359.41 136.525 0)
			(effects
				(font
					(size 1.27 1.27)
				)
			)
		)
		(property "MPN" "ERJ2GE0R00X"
			(at 379.73 116.205 0)
			(effects
				(font
					(size 1.27 1.27)
					(thickness 0.15)
				)
				(justify left bottom)
				(hide yes)
			)
		)
		(property "Manufacturer" "Panasonic"
			(at 382.27 116.205 0)
			(effects
				(font
					(size 1.27 1.27)
					(thickness 0.15)
				)
				(justify left bottom)
				(hide yes)
			)
		)
		(property "License" "Apache-2.0"
			(at 384.81 116.205 0)
			(effects
				(font
					(size 1.27 1.27)
					(thickness 0.15)
				)
				(justify left bottom)
				(hide yes)
			)
		)
		(property "Author" "Antmicro"
			(at 387.35 116.205 0)
			(effects
				(font
					(size 1.27 1.27)
					(thickness 0.15)
				)
				(justify left bottom)
				(hide yes)
			)
		)
		(property "Val" "0R"
			(at 358.14 130.175 0)
			(effects
				(font
					(size 1.27 1.27)
					(thickness 0.15)
				)
			)
		)
		(property "Tolerance" "~"
			(at 369.57 116.205 0)
			(effects
				(font
					(size 1.27 1.27)
				)
				(justify left bottom)
				(hide yes)
			)
		)
		(property "Current" "1A"
			(at 389.89 116.205 0)
			(effects
				(font
					(size 1.27 1.27)
					(thickness 0.15)
				)
				(justify left bottom)
				(hide yes)
			)
		)
		(pin "1"
		)
		(pin "2"
		)
		(instances
			(project "sodimm-ddr5-tester"
				(path ""
					(reference "R30")
					(unit 1)
				)
			)
		)
	)
	(symbol
		(lib_id "antmicroCapacitors0402:C_1u_0402")
		(at 172.72 220.345 270)
		(unit 1)
		(exclude_from_sim no)
		(in_bom no)
		(on_board yes)
		(dnp yes)
		(property "Reference" "C127"
			(at 175.895 221.615 90)
			(effects
				(font
					(size 1.27 1.27)
				)
				(justify left)
			)
		)
		(property "Value" "C_1u_0402"
			(at 162.56 240.665 0)
			(effects
				(font
					(size 1.27 1.27)
					(thickness 0.15)
				)
				(justify left bottom)
				(hide yes)
			)
		)
		(property "Footprint" "antmicro-footprints:C_0402_1005Metric"
			(at 160.02 240.665 0)
			(effects
				(font
					(size 1.27 1.27)
					(thickness 0.15)
				)
				(justify left bottom)
				(hide yes)
			)
		)
		(property "Datasheet" "https://product.tdk.com/en/search/capacitor/ceramic/mlcc/info?part_no=C1005X6S1A105K050BC"
			(at 157.48 240.665 0)
			(effects
				(font
					(size 1.27 1.27)
					(thickness 0.15)
				)
				(justify left bottom)
				(hide yes)
			)
		)
		(property "Description" ""
			(at 172.72 220.345 0)
			(effects
				(font
					(size 1.27 1.27)
				)
			)
		)
		(property "Manufacturer" "TDK"
			(at 152.4 240.665 0)
			(effects
				(font
					(size 1.27 1.27)
					(thickness 0.15)
				)
				(justify left bottom)
				(hide yes)
			)
		)
		(property "MPN" "C1005X6S1A105K050BC"
			(at 154.94 240.665 0)
			(effects
				(font
					(size 1.27 1.27)
					(thickness 0.15)
				)
				(justify left bottom)
				(hide yes)
			)
		)
		(property "Val" "1u"
			(at 175.895 223.5262 90)
			(effects
				(font
					(size 1.27 1.27)
					(thickness 0.15)
				)
				(justify left)
			)
		)
		(property "License" "Apache-2.0"
			(at 149.86 240.665 0)
			(effects
				(font
					(size 1.27 1.27)
					(thickness 0.15)
				)
				(justify left bottom)
				(hide yes)
			)
		)
		(property "Author" "Antmicro"
			(at 147.32 240.665 0)
			(effects
				(font
					(size 1.27 1.27)
					(thickness 0.15)
				)
				(justify left bottom)
				(hide yes)
			)
		)
		(property "Voltage" ""
			(at 144.78 240.665 0)
			(effects
				(font
					(size 1.27 1.27)
				)
				(justify left bottom)
				(hide yes)
			)
		)
		(property "Dielectric" ""
			(at 142.24 240.665 0)
			(effects
				(font
					(size 1.27 1.27)
				)
				(justify left bottom)
				(hide yes)
			)
		)
		(pin "1"
		)
		(pin "2"
		)
		(instances
			(project "sodimm-ddr5-tester"
				(path ""
					(reference "C127")
					(unit 1)
				)
			)
		)
	)
	(symbol
		(lib_id "antmicroCapacitors0402:C_4u7_0402")
		(at 278.13 54.61 270)
		(unit 1)
		(exclude_from_sim no)
		(in_bom yes)
		(on_board yes)
		(dnp no)
		(fields_autoplaced yes)
		(property "Reference" "C7"
			(at 280.67 55.8863 90)
			(effects
				(font
					(size 1.27 1.27)
				)
				(justify left)
			)
		)
		(property "Value" "C_4u7_0402"
			(at 267.97 74.93 0)
			(effects
				(font
					(size 1.27 1.27)
					(thickness 0.15)
				)
				(justify left bottom)
				(hide yes)
			)
		)
		(property "Footprint" "antmicro-footprints:C_0402_1005Metric"
			(at 265.43 74.93 0)
			(effects
				(font
					(size 1.27 1.27)
					(thickness 0.15)
				)
				(justify left bottom)
				(hide yes)
			)
		)
		(property "Datasheet" "https://www.murata.com/products/productdetail?partno=GRM155R61A475MEAA%23"
			(at 262.89 74.93 0)
			(effects
				(font
					(size 1.27 1.27)
					(thickness 0.15)
				)
				(justify left bottom)
				(hide yes)
			)
		)
		(property "Description" ""
			(at 278.13 54.61 0)
			(effects
				(font
					(size 1.27 1.27)
				)
			)
		)
		(property "Manufacturer" "Murata"
			(at 257.81 74.93 0)
			(effects
				(font
					(size 1.27 1.27)
					(thickness 0.15)
				)
				(justify left bottom)
				(hide yes)
			)
		)
		(property "MPN" "GRM155R61A475MEAAD"
			(at 260.35 74.93 0)
			(effects
				(font
					(size 1.27 1.27)
					(thickness 0.15)
				)
				(justify left bottom)
				(hide yes)
			)
		)
		(property "Val" "4u7"
			(at 280.67 59.0612 90)
			(effects
				(font
					(size 1.27 1.27)
					(thickness 0.15)
				)
				(justify left)
			)
		)
		(property "License" "Apache-2.0"
			(at 255.27 74.93 0)
			(effects
				(font
					(size 1.27 1.27)
					(thickness 0.15)
				)
				(justify left bottom)
				(hide yes)
			)
		)
		(property "Author" "Antmicro"
			(at 252.73 74.93 0)
			(effects
				(font
					(size 1.27 1.27)
					(thickness 0.15)
				)
				(justify left bottom)
				(hide yes)
			)
		)
		(property "Voltage" ""
			(at 250.19 74.93 0)
			(effects
				(font
					(size 1.27 1.27)
				)
				(justify left bottom)
				(hide yes)
			)
		)
		(property "Dielectric" ""
			(at 247.65 74.93 0)
			(effects
				(font
					(size 1.27 1.27)
				)
				(justify left bottom)
				(hide yes)
			)
		)
		(pin "1"
		)
		(pin "2"
		)
		(instances
			(project "sodimm-ddr5-tester"
				(path ""
					(reference "C7")
					(unit 1)
				)
			)
		)
	)
	(symbol
		(lib_id "antmicropower:+3V3")
		(at 164.465 204.47 0)
		(unit 1)
		(exclude_from_sim no)
		(in_bom yes)
		(on_board yes)
		(dnp no)
		(fields_autoplaced yes)
		(property "Reference" "#PWR0210"
			(at 164.465 208.28 0)
			(effects
				(font
					(size 1.27 1.27)
				)
				(hide yes)
			)
		)
		(property "Value" "+3V3"
			(at 161.29 201.93 0)
			(effects
				(font
					(size 1.27 1.27)
					(thickness 0.15)
				)
				(justify left bottom)
			)
		)
		(property "Footprint" ""
			(at 179.705 212.09 0)
			(effects
				(font
					(size 1.27 1.27)
					(thickness 0.15)
				)
				(justify left bottom)
				(hide yes)
			)
		)
		(property "Datasheet" ""
			(at 179.705 214.63 0)
			(effects
				(font
					(size 1.27 1.27)
					(thickness 0.15)
				)
				(justify left bottom)
				(hide yes)
			)
		)
		(property "Description" ""
			(at 164.465 204.47 0)
			(effects
				(font
					(size 1.27 1.27)
				)
			)
		)
		(property "Author" "Antmicro"
			(at 179.705 207.01 0)
			(effects
				(font
					(size 1.27 1.27)
					(thickness 0.15)
				)
				(justify left bottom)
				(hide yes)
			)
		)
		(property "License" "Apache-2.0"
			(at 179.705 209.55 0)
			(effects
				(font
					(size 1.27 1.27)
					(thickness 0.15)
				)
				(justify left bottom)
				(hide yes)
			)
		)
		(pin "1"
		)
		(instances
			(project "sodimm-ddr5-tester"
				(path ""
					(reference "#PWR0210")
					(unit 1)
				)
			)
		)
	)
	(symbol
		(lib_id "antmicropower:GND")
		(at 351.155 224.79 0)
		(unit 1)
		(exclude_from_sim no)
		(in_bom yes)
		(on_board yes)
		(dnp no)
		(property "Reference" "#PWR047"
			(at 351.155 231.14 0)
			(effects
				(font
					(size 1.27 1.27)
				)
				(hide yes)
			)
		)
		(property "Value" "GND"
			(at 348.996 228.6 0)
			(effects
				(font
					(size 1.27 1.27)
					(thickness 0.15)
				)
				(justify left)
			)
		)
		(property "Footprint" ""
			(at 360.045 232.41 0)
			(effects
				(font
					(size 1.27 1.27)
					(thickness 0.15)
				)
				(justify left bottom)
				(hide yes)
			)
		)
		(property "Datasheet" ""
			(at 360.045 237.49 0)
			(effects
				(font
					(size 1.27 1.27)
					(thickness 0.15)
				)
				(justify left bottom)
				(hide yes)
			)
		)
		(property "Description" ""
			(at 360.045 240.03 0)
			(effects
				(font
					(size 1.27 1.27)
				)
				(justify left bottom)
				(hide yes)
			)
		)
		(property "Author" "Antmicro"
			(at 360.045 232.41 0)
			(effects
				(font
					(size 1.27 1.27)
					(thickness 0.15)
				)
				(justify left bottom)
				(hide yes)
			)
		)
		(property "License" "Apache-2.0"
			(at 360.045 234.95 0)
			(effects
				(font
					(size 1.27 1.27)
					(thickness 0.15)
				)
				(justify left bottom)
				(hide yes)
			)
		)
		(pin "1"
		)
		(instances
			(project "sodimm-ddr5-tester"
				(path ""
					(reference "#PWR047")
					(unit 1)
				)
			)
		)
	)
	(symbol
		(lib_id "antmicropower:+1V1")
		(at 351.155 217.17 0)
		(unit 1)
		(exclude_from_sim no)
		(in_bom yes)
		(on_board yes)
		(dnp no)
		(fields_autoplaced yes)
		(property "Reference" "#PWR046"
			(at 351.155 220.98 0)
			(effects
				(font
					(size 1.27 1.27)
				)
				(hide yes)
			)
		)
		(property "Value" "+1V1"
			(at 351.155 213.614 0)
			(effects
				(font
					(size 1.27 1.27)
				)
			)
		)
		(property "Footprint" ""
			(at 351.155 217.17 0)
			(effects
				(font
					(size 1.27 1.27)
				)
				(hide yes)
			)
		)
		(property "Datasheet" ""
			(at 351.155 217.17 0)
			(effects
				(font
					(size 1.27 1.27)
				)
				(hide yes)
			)
		)
		(property "Description" ""
			(at 351.155 217.17 0)
			(effects
				(font
					(size 1.27 1.27)
				)
			)
		)
		(pin "1"
		)
		(instances
			(project "sodimm-ddr5-tester"
				(path ""
					(reference "#PWR046")
					(unit 1)
				)
			)
		)
	)
	(symbol
		(lib_id "antmicroResistors0402:R_0R_0402")
		(at 334.01 71.12 0)
		(mirror y)
		(unit 1)
		(exclude_from_sim no)
		(in_bom yes)
		(on_board yes)
		(dnp no)
		(property "Reference" "R31"
			(at 335.28 69.85 0)
			(effects
				(font
					(size 1.27 1.27)
					(thickness 0.15)
				)
			)
		)
		(property "Value" "R_0R_0402"
			(at 313.69 83.82 0)
			(effects
				(font
					(size 1.27 1.27)
					(thickness 0.15)
				)
				(justify left bottom)
				(hide yes)
			)
		)
		(property "Footprint" "antmicro-footprints:R_0402_1005Metric"
			(at 313.69 86.36 0)
			(effects
				(font
					(size 1.27 1.27)
					(thickness 0.15)
				)
				(justify left bottom)
				(hide yes)
			)
		)
		(property "Datasheet" "https://industrial.panasonic.com/cdbs/www-data/pdf/RDA0000/AOA0000C301.pdf"
			(at 313.69 88.9 0)
			(effects
				(font
					(size 1.27 1.27)
					(thickness 0.15)
				)
				(justify left bottom)
				(hide yes)
			)
		)
		(property "Description" ""
			(at 334.01 71.12 0)
			(effects
				(font
					(size 1.27 1.27)
				)
			)
		)
		(property "MPN" "ERJ2GE0R00X"
			(at 313.69 91.44 0)
			(effects
				(font
					(size 1.27 1.27)
					(thickness 0.15)
				)
				(justify left bottom)
				(hide yes)
			)
		)
		(property "Manufacturer" "Panasonic"
			(at 313.69 93.98 0)
			(effects
				(font
					(size 1.27 1.27)
					(thickness 0.15)
				)
				(justify left bottom)
				(hide yes)
			)
		)
		(property "License" "Apache-2.0"
			(at 313.69 96.52 0)
			(effects
				(font
					(size 1.27 1.27)
					(thickness 0.15)
				)
				(justify left bottom)
				(hide yes)
			)
		)
		(property "Author" "Antmicro"
			(at 313.69 99.06 0)
			(effects
				(font
					(size 1.27 1.27)
					(thickness 0.15)
				)
				(justify left bottom)
				(hide yes)
			)
		)
		(property "Val" "0R"
			(at 327.66 69.85 0)
			(effects
				(font
					(size 1.27 1.27)
					(thickness 0.15)
				)
			)
		)
		(property "Tolerance" "~"
			(at 313.69 81.28 0)
			(effects
				(font
					(size 1.27 1.27)
				)
				(justify left bottom)
				(hide yes)
			)
		)
		(property "Current" "1A"
			(at 313.69 101.6 0)
			(effects
				(font
					(size 1.27 1.27)
					(thickness 0.15)
				)
				(justify left bottom)
				(hide yes)
			)
		)
		(pin "1"
		)
		(pin "2"
		)
		(instances
			(project "sodimm-ddr5-tester"
				(path ""
					(reference "R31")
					(unit 1)
				)
			)
		)
	)
	(symbol
		(lib_id "antmicropower:GND")
		(at 340.995 224.79 0)
		(unit 1)
		(exclude_from_sim no)
		(in_bom yes)
		(on_board yes)
		(dnp no)
		(property "Reference" "#PWR045"
			(at 340.995 231.14 0)
			(effects
				(font
					(size 1.27 1.27)
				)
				(hide yes)
			)
		)
		(property "Value" "GND"
			(at 338.836 228.6 0)
			(effects
				(font
					(size 1.27 1.27)
					(thickness 0.15)
				)
				(justify left)
			)
		)
		(property "Footprint" ""
			(at 349.885 232.41 0)
			(effects
				(font
					(size 1.27 1.27)
					(thickness 0.15)
				)
				(justify left bottom)
				(hide yes)
			)
		)
		(property "Datasheet" ""
			(at 349.885 237.49 0)
			(effects
				(font
					(size 1.27 1.27)
					(thickness 0.15)
				)
				(justify left bottom)
				(hide yes)
			)
		)
		(property "Description" ""
			(at 349.885 240.03 0)
			(effects
				(font
					(size 1.27 1.27)
				)
				(justify left bottom)
				(hide yes)
			)
		)
		(property "Author" "Antmicro"
			(at 349.885 232.41 0)
			(effects
				(font
					(size 1.27 1.27)
					(thickness 0.15)
				)
				(justify left bottom)
				(hide yes)
			)
		)
		(property "License" "Apache-2.0"
			(at 349.885 234.95 0)
			(effects
				(font
					(size 1.27 1.27)
					(thickness 0.15)
				)
				(justify left bottom)
				(hide yes)
			)
		)
		(pin "1"
		)
		(instances
			(project "sodimm-ddr5-tester"
				(path ""
					(reference "#PWR045")
					(unit 1)
				)
			)
		)
	)
	(symbol
		(lib_id "antmicroTransistorsFETsMOSFETsSingle:BSS138PW,115")
		(at 78.74 237.49 0)
		(unit 1)
		(exclude_from_sim no)
		(in_bom yes)
		(on_board yes)
		(dnp no)
		(property "Reference" "Q10"
			(at 88.9 233.68 0)
			(effects
				(font
					(size 1.27 1.27)
					(thickness 0.15)
				)
				(justify left)
			)
		)
		(property "Value" "BSS138PW,115"
			(at 101.6 246.38 0)
			(effects
				(font
					(size 1.27 1.27)
					(thickness 0.15)
				)
				(justify left bottom)
				(hide yes)
			)
		)
		(property "Footprint" "antmicro-footprints:SC70-3"
			(at 101.6 248.92 0)
			(effects
				(font
					(size 1.27 1.27)
					(thickness 0.15)
				)
				(justify left bottom)
				(hide yes)
			)
		)
		(property "Datasheet" "https://assets.nexperia.com/documents/data-sheet/BSS138PW.pdf"
			(at 101.6 251.46 0)
			(effects
				(font
					(size 1.27 1.27)
					(thickness 0.15)
				)
				(justify left bottom)
				(hide yes)
			)
		)
		(property "Description" "Power MOSFET, N Channel, 60 V, 320 mA, 0.9 ohm, SOT-323, Surface Mount"
			(at 101.6 264.16 0)
			(effects
				(font
					(size 1.27 1.27)
				)
				(justify left bottom)
				(hide yes)
			)
		)
		(property "MPN" "BSS138PW,115"
			(at 88.9 236.22 0)
			(effects
				(font
					(size 1.27 1.27)
					(thickness 0.15)
				)
				(justify left)
			)
		)
		(property "Manufacturer" "Nexperia"
			(at 101.6 256.54 0)
			(effects
				(font
					(size 1.27 1.27)
					(thickness 0.15)
				)
				(justify left bottom)
				(hide yes)
			)
		)
		(property "Author" "Antmicro"
			(at 101.6 259.08 0)
			(effects
				(font
					(size 1.27 1.27)
					(thickness 0.15)
				)
				(justify left bottom)
				(hide yes)
			)
		)
		(property "License" "Apache-2.0"
			(at 101.6 261.62 0)
			(effects
				(font
					(size 1.27 1.27)
					(thickness 0.15)
				)
				(justify left bottom)
				(hide yes)
			)
		)
		(pin "3"
		)
		(pin "2"
		)
		(pin "1"
		)
		(instances
			(project "sodimm-ddr5-tester"
				(path ""
					(reference "Q10")
					(unit 1)
				)
			)
		)
	)
	(symbol
		(lib_id "antmicroResistors0402:R_4k7_0402")
		(at 164.465 207.01 270)
		(unit 1)
		(exclude_from_sim no)
		(in_bom yes)
		(on_board yes)
		(dnp no)
		(fields_autoplaced yes)
		(property "Reference" "R78"
			(at 162.56 208.28 90)
			(effects
				(font
					(size 1.27 1.27)
				)
				(justify right)
			)
		)
		(property "Value" "R_4k7_0402"
			(at 151.765 227.33 0)
			(effects
				(font
					(size 1.27 1.27)
					(thickness 0.15)
				)
				(justify left bottom)
				(hide yes)
			)
		)
		(property "Footprint" "antmicro-footprints:R_0402_1005Metric"
			(at 149.225 227.33 0)
			(effects
				(font
					(size 1.27 1.27)
					(thickness 0.15)
				)
				(justify left bottom)
				(hide yes)
			)
		)
		(property "Datasheet" "https://www.bourns.com/docs/product-datasheets/cr.pdf"
			(at 146.685 227.33 0)
			(effects
				(font
					(size 1.27 1.27)
					(thickness 0.15)
				)
				(justify left bottom)
				(hide yes)
			)
		)
		(property "Description" ""
			(at 164.465 207.01 0)
			(effects
				(font
					(size 1.27 1.27)
				)
			)
		)
		(property "Manufacturer" "Bourns"
			(at 141.605 227.33 0)
			(effects
				(font
					(size 1.27 1.27)
					(thickness 0.15)
				)
				(justify left bottom)
				(hide yes)
			)
		)
		(property "MPN" "CR0402-FX-4701GLF"
			(at 144.145 227.33 0)
			(effects
				(font
					(size 1.27 1.27)
					(thickness 0.15)
				)
				(justify left bottom)
				(hide yes)
			)
		)
		(property "Val" "4k7"
			(at 162.56 211.4549 90)
			(effects
				(font
					(size 1.27 1.27)
					(thickness 0.15)
				)
				(justify right)
			)
		)
		(property "License" "Apache-2.0"
			(at 139.065 227.33 0)
			(effects
				(font
					(size 1.27 1.27)
					(thickness 0.15)
				)
				(justify left bottom)
				(hide yes)
			)
		)
		(property "Author" "Antmicro"
			(at 136.525 227.33 0)
			(effects
				(font
					(size 1.27 1.27)
					(thickness 0.15)
				)
				(justify left bottom)
				(hide yes)
			)
		)
		(property "Tolerance" "1%"
			(at 154.305 227.33 0)
			(effects
				(font
					(size 1.27 1.27)
				)
				(justify left bottom)
				(hide yes)
			)
		)
		(pin "1"
		)
		(pin "2"
		)
		(instances
			(project "sodimm-ddr5-tester"
				(path ""
					(reference "R78")
					(unit 1)
				)
			)
		)
	)
	(symbol
		(lib_id "antmicroResistors0402:R_10k_0402")
		(at 269.875 227.965 90)
		(unit 1)
		(exclude_from_sim no)
		(in_bom yes)
		(on_board yes)
		(dnp no)
		(fields_autoplaced yes)
		(property "Reference" "R128"
			(at 271.526 224.5944 90)
			(effects
				(font
					(size 1.27 1.27)
					(thickness 0.15)
				)
				(justify right)
			)
		)
		(property "Value" "R_10k_0402"
			(at 282.575 207.645 0)
			(effects
				(font
					(size 1.27 1.27)
					(thickness 0.15)
				)
				(justify left bottom)
				(hide yes)
			)
		)
		(property "Footprint" "antmicro-footprints:R_0402_1005Metric"
			(at 285.115 207.645 0)
			(effects
				(font
					(size 1.27 1.27)
					(thickness 0.15)
				)
				(justify left bottom)
				(hide yes)
			)
		)
		(property "Datasheet" "https://www.bourns.com/docs/product-datasheets/cr.pdf"
			(at 287.655 207.645 0)
			(effects
				(font
					(size 1.27 1.27)
					(thickness 0.15)
				)
				(justify left bottom)
				(hide yes)
			)
		)
		(property "Description" ""
			(at 269.875 227.965 0)
			(effects
				(font
					(size 1.27 1.27)
				)
			)
		)
		(property "MPN" "CR0402-FX-1002GLF"
			(at 290.195 207.645 0)
			(effects
				(font
					(size 1.27 1.27)
					(thickness 0.15)
				)
				(justify left bottom)
				(hide yes)
			)
		)
		(property "Manufacturer" "Bourns"
			(at 292.735 207.645 0)
			(effects
				(font
					(size 1.27 1.27)
					(thickness 0.15)
				)
				(justify left bottom)
				(hide yes)
			)
		)
		(property "License" "Apache-2.0"
			(at 295.275 207.645 0)
			(effects
				(font
					(size 1.27 1.27)
					(thickness 0.15)
				)
				(justify left bottom)
				(hide yes)
			)
		)
		(property "Author" "Antmicro"
			(at 297.815 207.645 0)
			(effects
				(font
					(size 1.27 1.27)
					(thickness 0.15)
				)
				(justify left bottom)
				(hide yes)
			)
		)
		(property "Val" "10k"
			(at 271.526 227.1181 90)
			(effects
				(font
					(size 1.27 1.27)
					(thickness 0.15)
				)
				(justify right)
			)
		)
		(property "Tolerance" "1%"
			(at 280.035 207.645 0)
			(effects
				(font
					(size 1.27 1.27)
				)
				(justify left bottom)
				(hide yes)
			)
		)
		(pin "1"
		)
		(pin "2"
		)
		(instances
			(project "sodimm-ddr5-tester"
				(path ""
					(reference "R128")
					(unit 1)
				)
			)
		)
	)
	(symbol
		(lib_id "antmicroPushbuttonSwitches:SW_KMR211NGLFS_SMD")
		(at 161.925 226.06 90)
		(unit 1)
		(exclude_from_sim no)
		(in_bom yes)
		(on_board yes)
		(dnp no)
		(property "Reference" "SW3"
			(at 144.78 222.25 90)
			(effects
				(font
					(size 1.27 1.27)
					(thickness 0.15)
				)
				(justify right)
			)
		)
		(property "Value" "SW_KMR211NGLFS_SMD"
			(at 169.545 200.66 0)
			(effects
				(font
					(size 1.27 1.27)
					(thickness 0.15)
				)
				(justify left bottom)
				(hide yes)
			)
		)
		(property "Footprint" "antmicro-footprints:SW_KMR211NGLFS_SMD"
			(at 172.085 200.66 0)
			(effects
				(font
					(size 1.27 1.27)
					(thickness 0.15)
				)
				(justify left bottom)
				(hide yes)
			)
		)
		(property "Datasheet" "http://www.farnell.com/datasheets/2631211.pdf"
			(at 174.625 200.66 0)
			(effects
				(font
					(size 1.27 1.27)
					(thickness 0.15)
				)
				(justify left bottom)
				(hide yes)
			)
		)
		(property "Description" ""
			(at 161.925 226.06 0)
			(effects
				(font
					(size 1.27 1.27)
				)
			)
		)
		(property "MPN" "KMR211NGLFS"
			(at 144.78 224.79 90)
			(effects
				(font
					(size 1.27 1.27)
					(thickness 0.15)
				)
				(justify right)
			)
		)
		(property "Manufacturer" "C&K"
			(at 177.165 200.66 0)
			(effects
				(font
					(size 1.27 1.27)
					(thickness 0.15)
				)
				(justify left bottom)
				(hide yes)
			)
		)
		(property "Author" "Antmicro"
			(at 179.705 200.66 0)
			(effects
				(font
					(size 1.27 1.27)
					(thickness 0.15)
				)
				(justify left bottom)
				(hide yes)
			)
		)
		(property "License" "Apache-2.0"
			(at 182.245 200.66 0)
			(effects
				(font
					(size 1.27 1.27)
					(thickness 0.15)
				)
				(justify left bottom)
				(hide yes)
			)
		)
		(pin "1"
		)
		(pin "2"
		)
		(pin "3"
		)
		(pin "4"
		)
		(instances
			(project "sodimm-ddr5-tester"
				(path ""
					(reference "SW3")
					(unit 1)
				)
			)
		)
	)
	(symbol
		(lib_id "antmicroMemoryConnectorsPCCardSockets:Bus_DDR5_SODIMM_Amphenol_10161033-002RHLF_CUSTOM_2xDetectPin")
		(at 288.29 66.04 0)
		(unit 3)
		(exclude_from_sim no)
		(in_bom yes)
		(on_board yes)
		(dnp no)
		(fields_autoplaced yes)
		(property "Reference" "J2"
			(at 302.26 59.815 0)
			(effects
				(font
					(size 1.27 1.27)
					(thickness 0.15)
				)
			)
		)
		(property "Value" "Bus_DDR5_SODIMM_Amphenol_10161033-002RHLF_CUSTOM_2xDetectPin"
			(at 339.09 73.66 0)
			(effects
				(font
					(size 1.27 1.27)
					(thickness 0.15)
				)
				(justify left bottom)
				(hide yes)
			)
		)
		(property "Footprint" "antmicro-footprints:Bus_DDR5_SODIMM_Amphenol_10161033-002RHLF"
			(at 339.09 76.2 0)
			(effects
				(font
					(size 1.27 1.27)
					(thickness 0.15)
				)
				(justify left bottom)
				(hide yes)
			)
		)
		(property "Datasheet" "https://cdn.amphenol-cs.com/media/wysiwyg/files/documentation/datasheet/ssio/ssio_ddr5_sodimm.pdf"
			(at 339.09 78.74 0)
			(effects
				(font
					(size 1.27 1.27)
					(thickness 0.15)
				)
				(justify left bottom)
				(hide yes)
			)
		)
		(property "Description" ""
			(at 288.29 66.04 0)
			(effects
				(font
					(size 1.27 1.27)
				)
			)
		)
		(property "MPN" "10161033-002RHLF"
			(at 302.26 62.3387 0)
			(effects
				(font
					(size 1.27 1.27)
					(thickness 0.15)
				)
			)
		)
		(property "Manufacturer" "Amphenol"
			(at 339.09 81.28 0)
			(effects
				(font
					(size 1.27 1.27)
					(thickness 0.15)
				)
				(justify left bottom)
				(hide yes)
			)
		)
		(property "Author" "Antmicro"
			(at 339.09 83.82 0)
			(effects
				(font
					(size 1.27 1.27)
					(thickness 0.15)
				)
				(justify left bottom)
				(hide yes)
			)
		)
		(property "License" "Apache-2.0"
			(at 339.09 86.36 0)
			(effects
				(font
					(size 1.27 1.27)
					(thickness 0.15)
				)
				(justify left bottom)
				(hide yes)
			)
		)
		(pin "100"
		)
		(pin "102"
		)
		(pin "103"
		)
		(pin "106"
		)
		(pin "107"
		)
		(pin "109"
		)
		(pin "11"
		)
		(pin "110"
		)
		(pin "113"
		)
		(pin "114"
		)
		(pin "115"
		)
		(pin "116"
		)
		(pin "119"
		)
		(pin "12"
		)
		(pin "120"
		)
		(pin "121"
		)
		(pin "122"
		)
		(pin "125"
		)
		(pin "126"
		)
		(pin "127"
		)
		(pin "131"
		)
		(pin "132"
		)
		(pin "133"
		)
		(pin "134"
		)
		(pin "15"
		)
		(pin "16"
		)
		(pin "19"
		)
		(pin "20"
		)
		(pin "22"
		)
		(pin "23"
		)
		(pin "26"
		)
		(pin "27"
		)
		(pin "30"
		)
		(pin "31"
		)
		(pin "34"
		)
		(pin "35"
		)
		(pin "38"
		)
		(pin "39"
		)
		(pin "41"
		)
		(pin "42"
		)
		(pin "45"
		)
		(pin "46"
		)
		(pin "49"
		)
		(pin "50"
		)
		(pin "53"
		)
		(pin "54"
		)
		(pin "57"
		)
		(pin "58"
		)
		(pin "61"
		)
		(pin "62"
		)
		(pin "64"
		)
		(pin "65"
		)
		(pin "68"
		)
		(pin "69"
		)
		(pin "72"
		)
		(pin "73"
		)
		(pin "76"
		)
		(pin "77"
		)
		(pin "80"
		)
		(pin "81"
		)
		(pin "83"
		)
		(pin "84"
		)
		(pin "87"
		)
		(pin "88"
		)
		(pin "91"
		)
		(pin "92"
		)
		(pin "95"
		)
		(pin "96"
		)
		(pin "99"
		)
		(pin "137"
		)
		(pin "138"
		)
		(pin "139"
		)
		(pin "140"
		)
		(pin "144"
		)
		(pin "145"
		)
		(pin "146"
		)
		(pin "149"
		)
		(pin "150"
		)
		(pin "151"
		)
		(pin "152"
		)
		(pin "155"
		)
		(pin "156"
		)
		(pin "157"
		)
		(pin "158"
		)
		(pin "161"
		)
		(pin "162"
		)
		(pin "164"
		)
		(pin "165"
		)
		(pin "168"
		)
		(pin "169"
		)
		(pin "171"
		)
		(pin "172"
		)
		(pin "175"
		)
		(pin "176"
		)
		(pin "179"
		)
		(pin "180"
		)
		(pin "183"
		)
		(pin "184"
		)
		(pin "187"
		)
		(pin "188"
		)
		(pin "190"
		)
		(pin "191"
		)
		(pin "194"
		)
		(pin "195"
		)
		(pin "198"
		)
		(pin "199"
		)
		(pin "202"
		)
		(pin "203"
		)
		(pin "206"
		)
		(pin "207"
		)
		(pin "209"
		)
		(pin "210"
		)
		(pin "213"
		)
		(pin "214"
		)
		(pin "217"
		)
		(pin "218"
		)
		(pin "221"
		)
		(pin "222"
		)
		(pin "225"
		)
		(pin "226"
		)
		(pin "229"
		)
		(pin "230"
		)
		(pin "232"
		)
		(pin "233"
		)
		(pin "236"
		)
		(pin "237"
		)
		(pin "240"
		)
		(pin "241"
		)
		(pin "244"
		)
		(pin "245"
		)
		(pin "248"
		)
		(pin "249"
		)
		(pin "251"
		)
		(pin "252"
		)
		(pin "255"
		)
		(pin "256"
		)
		(pin "259"
		)
		(pin "260"
		)
		(pin "1"
		)
		(pin "10"
		)
		(pin "101"
		)
		(pin "104"
		)
		(pin "105"
		)
		(pin "108"
		)
		(pin "111"
		)
		(pin "112"
		)
		(pin "117"
		)
		(pin "118"
		)
		(pin "123"
		)
		(pin "124"
		)
		(pin "128"
		)
		(pin "129"
		)
		(pin "13"
		)
		(pin "130"
		)
		(pin "135"
		)
		(pin "136"
		)
		(pin "14"
		)
		(pin "141"
		)
		(pin "142"
		)
		(pin "143"
		)
		(pin "147"
		)
		(pin "148"
		)
		(pin "153"
		)
		(pin "154"
		)
		(pin "159"
		)
		(pin "160"
		)
		(pin "163"
		)
		(pin "166"
		)
		(pin "167"
		)
		(pin "17"
		)
		(pin "170"
		)
		(pin "173"
		)
		(pin "174"
		)
		(pin "177"
		)
		(pin "178"
		)
		(pin "18"
		)
		(pin "181"
		)
		(pin "182"
		)
		(pin "185"
		)
		(pin "186"
		)
		(pin "189"
		)
		(pin "192"
		)
		(pin "193"
		)
		(pin "196"
		)
		(pin "197"
		)
		(pin "2"
		)
		(pin "200"
		)
		(pin "201"
		)
		(pin "204"
		)
		(pin "205"
		)
		(pin "208"
		)
		(pin "21"
		)
		(pin "211"
		)
		(pin "212"
		)
		(pin "215"
		)
		(pin "216"
		)
		(pin "219"
		)
		(pin "220"
		)
		(pin "223"
		)
		(pin "224"
		)
		(pin "227"
		)
		(pin "228"
		)
		(pin "231"
		)
		(pin "234"
		)
		(pin "235"
		)
		(pin "238"
		)
		(pin "239"
		)
		(pin "24"
		)
		(pin "242"
		)
		(pin "243"
		)
		(pin "246"
		)
		(pin "247"
		)
		(pin "25"
		)
		(pin "250"
		)
		(pin "253"
		)
		(pin "254"
		)
		(pin "257"
		)
		(pin "258"
		)
		(pin "261"
		)
		(pin "262"
		)
		(pin "28"
		)
		(pin "29"
		)
		(pin "3"
		)
		(pin "32"
		)
		(pin "33"
		)
		(pin "36"
		)
		(pin "37"
		)
		(pin "4"
		)
		(pin "40"
		)
		(pin "43"
		)
		(pin "44"
		)
		(pin "47"
		)
		(pin "48"
		)
		(pin "5"
		)
		(pin "51"
		)
		(pin "52"
		)
		(pin "55"
		)
		(pin "56"
		)
		(pin "59"
		)
		(pin "6"
		)
		(pin "60"
		)
		(pin "63"
		)
		(pin "66"
		)
		(pin "67"
		)
		(pin "7"
		)
		(pin "70"
		)
		(pin "71"
		)
		(pin "74"
		)
		(pin "75"
		)
		(pin "78"
		)
		(pin "79"
		)
		(pin "8"
		)
		(pin "82"
		)
		(pin "85"
		)
		(pin "86"
		)
		(pin "89"
		)
		(pin "9"
		)
		(pin "90"
		)
		(pin "93"
		)
		(pin "94"
		)
		(pin "97"
		)
		(pin "98"
		)
		(pin "SH"
		)
		(instances
			(project "sodimm-ddr5-tester"
				(path ""
					(reference "J2")
					(unit 3)
				)
			)
		)
	)
	(symbol
		(lib_id "antmicropower:+1V1")
		(at 361.95 217.17 0)
		(unit 1)
		(exclude_from_sim no)
		(in_bom yes)
		(on_board yes)
		(dnp no)
		(fields_autoplaced yes)
		(property "Reference" "#PWR048"
			(at 361.95 220.98 0)
			(effects
				(font
					(size 1.27 1.27)
				)
				(hide yes)
			)
		)
		(property "Value" "+1V1"
			(at 361.95 213.614 0)
			(effects
				(font
					(size 1.27 1.27)
				)
			)
		)
		(property "Footprint" ""
			(at 361.95 217.17 0)
			(effects
				(font
					(size 1.27 1.27)
				)
				(hide yes)
			)
		)
		(property "Datasheet" ""
			(at 361.95 217.17 0)
			(effects
				(font
					(size 1.27 1.27)
				)
				(hide yes)
			)
		)
		(property "Description" ""
			(at 361.95 217.17 0)
			(effects
				(font
					(size 1.27 1.27)
				)
			)
		)
		(pin "1"
		)
		(instances
			(project "sodimm-ddr5-tester"
				(path ""
					(reference "#PWR048")
					(unit 1)
				)
			)
		)
	)
	(symbol
		(lib_id "antmicroMemoryConnectorsPCCardSockets:Bus_DDR5_SODIMM_Amphenol_10161033-002RHLF_CUSTOM_2xDetectPin")
		(at 59.69 46.99 0)
		(unit 1)
		(exclude_from_sim no)
		(in_bom yes)
		(on_board yes)
		(dnp no)
		(fields_autoplaced yes)
		(property "Reference" "J2"
			(at 77.47 40.765 0)
			(effects
				(font
					(size 1.27 1.27)
					(thickness 0.15)
				)
			)
		)
		(property "Value" "Bus_DDR5_SODIMM_Amphenol_10161033-002RHLF_CUSTOM_2xDetectPin"
			(at 110.49 54.61 0)
			(effects
				(font
					(size 1.27 1.27)
					(thickness 0.15)
				)
				(justify left bottom)
				(hide yes)
			)
		)
		(property "Footprint" "antmicro-footprints:Bus_DDR5_SODIMM_Amphenol_10161033-002RHLF"
			(at 110.49 57.15 0)
			(effects
				(font
					(size 1.27 1.27)
					(thickness 0.15)
				)
				(justify left bottom)
				(hide yes)
			)
		)
		(property "Datasheet" "https://cdn.amphenol-cs.com/media/wysiwyg/files/documentation/datasheet/ssio/ssio_ddr5_sodimm.pdf"
			(at 110.49 59.69 0)
			(effects
				(font
					(size 1.27 1.27)
					(thickness 0.15)
				)
				(justify left bottom)
				(hide yes)
			)
		)
		(property "Description" ""
			(at 59.69 46.99 0)
			(effects
				(font
					(size 1.27 1.27)
				)
			)
		)
		(property "MPN" "10161033-002RHLF"
			(at 77.47 43.2887 0)
			(effects
				(font
					(size 1.27 1.27)
					(thickness 0.15)
				)
			)
		)
		(property "Manufacturer" "Amphenol"
			(at 110.49 62.23 0)
			(effects
				(font
					(size 1.27 1.27)
					(thickness 0.15)
				)
				(justify left bottom)
				(hide yes)
			)
		)
		(property "Author" "Antmicro"
			(at 110.49 64.77 0)
			(effects
				(font
					(size 1.27 1.27)
					(thickness 0.15)
				)
				(justify left bottom)
				(hide yes)
			)
		)
		(property "License" "Apache-2.0"
			(at 110.49 67.31 0)
			(effects
				(font
					(size 1.27 1.27)
					(thickness 0.15)
				)
				(justify left bottom)
				(hide yes)
			)
		)
		(pin "100"
		)
		(pin "102"
		)
		(pin "103"
		)
		(pin "106"
		)
		(pin "107"
		)
		(pin "109"
		)
		(pin "11"
		)
		(pin "110"
		)
		(pin "113"
		)
		(pin "114"
		)
		(pin "115"
		)
		(pin "116"
		)
		(pin "119"
		)
		(pin "12"
		)
		(pin "120"
		)
		(pin "121"
		)
		(pin "122"
		)
		(pin "125"
		)
		(pin "126"
		)
		(pin "127"
		)
		(pin "131"
		)
		(pin "132"
		)
		(pin "133"
		)
		(pin "134"
		)
		(pin "15"
		)
		(pin "16"
		)
		(pin "19"
		)
		(pin "20"
		)
		(pin "22"
		)
		(pin "23"
		)
		(pin "26"
		)
		(pin "27"
		)
		(pin "30"
		)
		(pin "31"
		)
		(pin "34"
		)
		(pin "35"
		)
		(pin "38"
		)
		(pin "39"
		)
		(pin "41"
		)
		(pin "42"
		)
		(pin "45"
		)
		(pin "46"
		)
		(pin "49"
		)
		(pin "50"
		)
		(pin "53"
		)
		(pin "54"
		)
		(pin "57"
		)
		(pin "58"
		)
		(pin "61"
		)
		(pin "62"
		)
		(pin "64"
		)
		(pin "65"
		)
		(pin "68"
		)
		(pin "69"
		)
		(pin "72"
		)
		(pin "73"
		)
		(pin "76"
		)
		(pin "77"
		)
		(pin "80"
		)
		(pin "81"
		)
		(pin "83"
		)
		(pin "84"
		)
		(pin "87"
		)
		(pin "88"
		)
		(pin "91"
		)
		(pin "92"
		)
		(pin "95"
		)
		(pin "96"
		)
		(pin "99"
		)
		(pin "137"
		)
		(pin "138"
		)
		(pin "139"
		)
		(pin "140"
		)
		(pin "144"
		)
		(pin "145"
		)
		(pin "146"
		)
		(pin "149"
		)
		(pin "150"
		)
		(pin "151"
		)
		(pin "152"
		)
		(pin "155"
		)
		(pin "156"
		)
		(pin "157"
		)
		(pin "158"
		)
		(pin "161"
		)
		(pin "162"
		)
		(pin "164"
		)
		(pin "165"
		)
		(pin "168"
		)
		(pin "169"
		)
		(pin "171"
		)
		(pin "172"
		)
		(pin "175"
		)
		(pin "176"
		)
		(pin "179"
		)
		(pin "180"
		)
		(pin "183"
		)
		(pin "184"
		)
		(pin "187"
		)
		(pin "188"
		)
		(pin "190"
		)
		(pin "191"
		)
		(pin "194"
		)
		(pin "195"
		)
		(pin "198"
		)
		(pin "199"
		)
		(pin "202"
		)
		(pin "203"
		)
		(pin "206"
		)
		(pin "207"
		)
		(pin "209"
		)
		(pin "210"
		)
		(pin "213"
		)
		(pin "214"
		)
		(pin "217"
		)
		(pin "218"
		)
		(pin "221"
		)
		(pin "222"
		)
		(pin "225"
		)
		(pin "226"
		)
		(pin "229"
		)
		(pin "230"
		)
		(pin "232"
		)
		(pin "233"
		)
		(pin "236"
		)
		(pin "237"
		)
		(pin "240"
		)
		(pin "241"
		)
		(pin "244"
		)
		(pin "245"
		)
		(pin "248"
		)
		(pin "249"
		)
		(pin "251"
		)
		(pin "252"
		)
		(pin "255"
		)
		(pin "256"
		)
		(pin "259"
		)
		(pin "260"
		)
		(pin "1"
		)
		(pin "10"
		)
		(pin "101"
		)
		(pin "104"
		)
		(pin "105"
		)
		(pin "108"
		)
		(pin "111"
		)
		(pin "112"
		)
		(pin "117"
		)
		(pin "118"
		)
		(pin "123"
		)
		(pin "124"
		)
		(pin "128"
		)
		(pin "129"
		)
		(pin "13"
		)
		(pin "130"
		)
		(pin "135"
		)
		(pin "136"
		)
		(pin "14"
		)
		(pin "141"
		)
		(pin "142"
		)
		(pin "143"
		)
		(pin "147"
		)
		(pin "148"
		)
		(pin "153"
		)
		(pin "154"
		)
		(pin "159"
		)
		(pin "160"
		)
		(pin "163"
		)
		(pin "166"
		)
		(pin "167"
		)
		(pin "17"
		)
		(pin "170"
		)
		(pin "173"
		)
		(pin "174"
		)
		(pin "177"
		)
		(pin "178"
		)
		(pin "18"
		)
		(pin "181"
		)
		(pin "182"
		)
		(pin "185"
		)
		(pin "186"
		)
		(pin "189"
		)
		(pin "192"
		)
		(pin "193"
		)
		(pin "196"
		)
		(pin "197"
		)
		(pin "2"
		)
		(pin "200"
		)
		(pin "201"
		)
		(pin "204"
		)
		(pin "205"
		)
		(pin "208"
		)
		(pin "21"
		)
		(pin "211"
		)
		(pin "212"
		)
		(pin "215"
		)
		(pin "216"
		)
		(pin "219"
		)
		(pin "220"
		)
		(pin "223"
		)
		(pin "224"
		)
		(pin "227"
		)
		(pin "228"
		)
		(pin "231"
		)
		(pin "234"
		)
		(pin "235"
		)
		(pin "238"
		)
		(pin "239"
		)
		(pin "24"
		)
		(pin "242"
		)
		(pin "243"
		)
		(pin "246"
		)
		(pin "247"
		)
		(pin "25"
		)
		(pin "250"
		)
		(pin "253"
		)
		(pin "254"
		)
		(pin "257"
		)
		(pin "258"
		)
		(pin "261"
		)
		(pin "262"
		)
		(pin "28"
		)
		(pin "29"
		)
		(pin "3"
		)
		(pin "32"
		)
		(pin "33"
		)
		(pin "36"
		)
		(pin "37"
		)
		(pin "4"
		)
		(pin "40"
		)
		(pin "43"
		)
		(pin "44"
		)
		(pin "47"
		)
		(pin "48"
		)
		(pin "5"
		)
		(pin "51"
		)
		(pin "52"
		)
		(pin "55"
		)
		(pin "56"
		)
		(pin "59"
		)
		(pin "6"
		)
		(pin "60"
		)
		(pin "63"
		)
		(pin "66"
		)
		(pin "67"
		)
		(pin "7"
		)
		(pin "70"
		)
		(pin "71"
		)
		(pin "74"
		)
		(pin "75"
		)
		(pin "78"
		)
		(pin "79"
		)
		(pin "8"
		)
		(pin "82"
		)
		(pin "85"
		)
		(pin "86"
		)
		(pin "89"
		)
		(pin "9"
		)
		(pin "90"
		)
		(pin "93"
		)
		(pin "94"
		)
		(pin "97"
		)
		(pin "98"
		)
		(pin "SH"
		)
		(instances
			(project "sodimm-ddr5-tester"
				(path ""
					(reference "J2")
					(unit 1)
				)
			)
		)
	)
	(symbol
		(lib_id "antmicropower:GND")
		(at 269.875 229.235 0)
		(mirror y)
		(unit 1)
		(exclude_from_sim no)
		(in_bom yes)
		(on_board yes)
		(dnp no)
		(property "Reference" "#PWR0275"
			(at 269.875 235.585 0)
			(effects
				(font
					(size 1.27 1.27)
				)
				(hide yes)
			)
		)
		(property "Value" "GND"
			(at 268.224 233.172 0)
			(effects
				(font
					(size 1.27 1.27)
					(thickness 0.15)
				)
				(justify right)
			)
		)
		(property "Footprint" ""
			(at 260.985 236.855 0)
			(effects
				(font
					(size 1.27 1.27)
					(thickness 0.15)
				)
				(justify left bottom)
				(hide yes)
			)
		)
		(property "Datasheet" ""
			(at 260.985 241.935 0)
			(effects
				(font
					(size 1.27 1.27)
					(thickness 0.15)
				)
				(justify left bottom)
				(hide yes)
			)
		)
		(property "Description" ""
			(at 260.985 244.475 0)
			(effects
				(font
					(size 1.27 1.27)
				)
				(justify left bottom)
				(hide yes)
			)
		)
		(property "Author" "Antmicro"
			(at 260.985 236.855 0)
			(effects
				(font
					(size 1.27 1.27)
					(thickness 0.15)
				)
				(justify left bottom)
				(hide yes)
			)
		)
		(property "License" "Apache-2.0"
			(at 260.985 239.395 0)
			(effects
				(font
					(size 1.27 1.27)
					(thickness 0.15)
				)
				(justify left bottom)
				(hide yes)
			)
		)
		(pin "1"
		)
		(instances
			(project "sodimm-ddr5-tester"
				(path ""
					(reference "#PWR0275")
					(unit 1)
				)
			)
		)
	)
	(symbol
		(lib_id "antmicroCapacitors0402:C_100n_0402")
		(at 340.995 223.52 90)
		(unit 1)
		(exclude_from_sim no)
		(in_bom yes)
		(on_board yes)
		(dnp no)
		(fields_autoplaced yes)
		(property "Reference" "C8"
			(at 343.3191 220.143 90)
			(effects
				(font
					(size 1.27 1.27)
					(thickness 0.15)
				)
				(justify right)
			)
		)
		(property "Value" "C_100n_0402"
			(at 351.155 203.2 0)
			(effects
				(font
					(size 1.27 1.27)
					(thickness 0.15)
				)
				(justify left bottom)
				(hide yes)
			)
		)
		(property "Footprint" "antmicro-footprints:C_0402_1005Metric"
			(at 353.695 203.2 0)
			(effects
				(font
					(size 1.27 1.27)
					(thickness 0.15)
				)
				(justify left bottom)
				(hide yes)
			)
		)
		(property "Datasheet" "https://www.murata.com/products/productdetail?partno=GRM155R61H104KE14%23"
			(at 356.235 203.2 0)
			(effects
				(font
					(size 1.27 1.27)
					(thickness 0.15)
				)
				(justify left bottom)
				(hide yes)
			)
		)
		(property "Description" ""
			(at 340.995 223.52 0)
			(effects
				(font
					(size 1.27 1.27)
				)
			)
		)
		(property "MPN" "GRM155R61H104KE14D"
			(at 358.775 203.2 0)
			(effects
				(font
					(size 1.27 1.27)
					(thickness 0.15)
				)
				(justify left bottom)
				(hide yes)
			)
		)
		(property "Manufacturer" "Murata"
			(at 361.315 203.2 0)
			(effects
				(font
					(size 1.27 1.27)
					(thickness 0.15)
				)
				(justify left bottom)
				(hide yes)
			)
		)
		(property "License" "Apache-2.0"
			(at 363.855 203.2 0)
			(effects
				(font
					(size 1.27 1.27)
					(thickness 0.15)
				)
				(justify left bottom)
				(hide yes)
			)
		)
		(property "Author" "Antmicro"
			(at 366.395 203.2 0)
			(effects
				(font
					(size 1.27 1.27)
					(thickness 0.15)
				)
				(justify left bottom)
				(hide yes)
			)
		)
		(property "Val" "100n"
			(at 343.3191 222.6667 90)
			(effects
				(font
					(size 1.27 1.27)
					(thickness 0.15)
				)
				(justify right)
			)
		)
		(property "Voltage" "50V"
			(at 368.935 203.2 0)
			(effects
				(font
					(size 1.27 1.27)
				)
				(justify left bottom)
				(hide yes)
			)
		)
		(property "Dielectric" "X5R"
			(at 371.475 203.2 0)
			(effects
				(font
					(size 1.27 1.27)
				)
				(justify left bottom)
				(hide yes)
			)
		)
		(pin "1"
		)
		(pin "2"
		)
		(instances
			(project "sodimm-ddr5-tester"
				(path ""
					(reference "C8")
					(unit 1)
				)
			)
		)
	)
	(symbol
		(lib_id "antmicropower:GND")
		(at 278.13 60.325 0)
		(unit 1)
		(exclude_from_sim no)
		(in_bom yes)
		(on_board yes)
		(dnp no)
		(fields_autoplaced yes)
		(property "Reference" "#PWR037"
			(at 278.13 66.675 0)
			(effects
				(font
					(size 1.27 1.27)
				)
				(hide yes)
			)
		)
		(property "Value" "GND"
			(at 280.67 61.595 0)
			(effects
				(font
					(size 1.27 1.27)
					(thickness 0.15)
				)
				(justify left)
			)
		)
		(property "Footprint" ""
			(at 287.02 67.945 0)
			(effects
				(font
					(size 1.27 1.27)
					(thickness 0.15)
				)
				(justify left bottom)
				(hide yes)
			)
		)
		(property "Datasheet" ""
			(at 287.02 73.025 0)
			(effects
				(font
					(size 1.27 1.27)
					(thickness 0.15)
				)
				(justify left bottom)
				(hide yes)
			)
		)
		(property "Description" ""
			(at 287.02 75.565 0)
			(effects
				(font
					(size 1.27 1.27)
				)
				(justify left bottom)
				(hide yes)
			)
		)
		(property "Author" "Antmicro"
			(at 287.02 67.945 0)
			(effects
				(font
					(size 1.27 1.27)
					(thickness 0.15)
				)
				(justify left bottom)
				(hide yes)
			)
		)
		(property "License" "Apache-2.0"
			(at 287.02 70.485 0)
			(effects
				(font
					(size 1.27 1.27)
					(thickness 0.15)
				)
				(justify left bottom)
				(hide yes)
			)
		)
		(pin "1"
		)
		(instances
			(project "sodimm-ddr5-tester"
				(path ""
					(reference "#PWR037")
					(unit 1)
				)
			)
		)
	)
	(symbol
		(lib_id "antmicroResistors0402:R_0R_0402")
		(at 367.665 117.475 0)
		(unit 1)
		(exclude_from_sim no)
		(in_bom no)
		(on_board yes)
		(dnp yes)
		(property "Reference" "R33"
			(at 374.65 116.205 0)
			(effects
				(font
					(size 1.27 1.27)
					(thickness 0.15)
				)
			)
		)
		(property "Value" "R_0R_0402"
			(at 387.985 130.175 0)
			(effects
				(font
					(size 1.27 1.27)
					(thickness 0.15)
				)
				(justify left bottom)
				(hide yes)
			)
		)
		(property "Footprint" "antmicro-footprints:R_0402_1005Metric"
			(at 387.985 132.715 0)
			(effects
				(font
					(size 1.27 1.27)
					(thickness 0.15)
				)
				(justify left bottom)
				(hide yes)
			)
		)
		(property "Datasheet" "https://industrial.panasonic.com/cdbs/www-data/pdf/RDA0000/AOA0000C301.pdf"
			(at 387.985 135.255 0)
			(effects
				(font
					(size 1.27 1.27)
					(thickness 0.15)
				)
				(justify left bottom)
				(hide yes)
			)
		)
		(property "Description" ""
			(at 367.665 117.475 0)
			(effects
				(font
					(size 1.27 1.27)
				)
			)
		)
		(property "MPN" "ERJ2GE0R00X"
			(at 387.985 137.795 0)
			(effects
				(font
					(size 1.27 1.27)
					(thickness 0.15)
				)
				(justify left bottom)
				(hide yes)
			)
		)
		(property "Manufacturer" "Panasonic"
			(at 387.985 140.335 0)
			(effects
				(font
					(size 1.27 1.27)
					(thickness 0.15)
				)
				(justify left bottom)
				(hide yes)
			)
		)
		(property "License" "Apache-2.0"
			(at 387.985 142.875 0)
			(effects
				(font
					(size 1.27 1.27)
					(thickness 0.15)
				)
				(justify left bottom)
				(hide yes)
			)
		)
		(property "Author" "Antmicro"
			(at 387.985 145.415 0)
			(effects
				(font
					(size 1.27 1.27)
					(thickness 0.15)
				)
				(justify left bottom)
				(hide yes)
			)
		)
		(property "Val" "0R"
			(at 366.395 116.205 0)
			(effects
				(font
					(size 1.27 1.27)
					(thickness 0.15)
				)
			)
		)
		(property "Tolerance" "~"
			(at 387.985 127.635 0)
			(effects
				(font
					(size 1.27 1.27)
				)
				(justify left bottom)
				(hide yes)
			)
		)
		(property "Current" "1A"
			(at 387.985 147.955 0)
			(effects
				(font
					(size 1.27 1.27)
					(thickness 0.15)
				)
				(justify left bottom)
				(hide yes)
			)
		)
		(pin "1"
		)
		(pin "2"
		)
		(instances
			(project "sodimm-ddr5-tester"
				(path ""
					(reference "R33")
					(unit 1)
				)
			)
		)
	)
	(symbol
		(lib_id "antmicropower:+1V1")
		(at 340.995 217.17 0)
		(unit 1)
		(exclude_from_sim no)
		(in_bom yes)
		(on_board yes)
		(dnp no)
		(fields_autoplaced yes)
		(property "Reference" "#PWR044"
			(at 340.995 220.98 0)
			(effects
				(font
					(size 1.27 1.27)
				)
				(hide yes)
			)
		)
		(property "Value" "+1V1"
			(at 340.995 213.614 0)
			(effects
				(font
					(size 1.27 1.27)
				)
			)
		)
		(property "Footprint" ""
			(at 340.995 217.17 0)
			(effects
				(font
					(size 1.27 1.27)
				)
				(hide yes)
			)
		)
		(property "Datasheet" ""
			(at 340.995 217.17 0)
			(effects
				(font
					(size 1.27 1.27)
				)
				(hide yes)
			)
		)
		(property "Description" ""
			(at 340.995 217.17 0)
			(effects
				(font
					(size 1.27 1.27)
				)
			)
		)
		(pin "1"
		)
		(instances
			(project "sodimm-ddr5-tester"
				(path ""
					(reference "#PWR044")
					(unit 1)
				)
			)
		)
	)
	(symbol
		(lib_id "antmicropower:GND")
		(at 104.14 251.46 0)
		(unit 1)
		(exclude_from_sim no)
		(in_bom yes)
		(on_board yes)
		(dnp no)
		(property "Reference" "#PWR0205"
			(at 104.14 257.81 0)
			(effects
				(font
					(size 1.27 1.27)
				)
				(hide yes)
			)
		)
		(property "Value" "GND"
			(at 102.362 255.524 0)
			(effects
				(font
					(size 1.27 1.27)
					(thickness 0.15)
				)
				(justify left)
			)
		)
		(property "Footprint" ""
			(at 113.03 259.08 0)
			(effects
				(font
					(size 1.27 1.27)
					(thickness 0.15)
				)
				(justify left bottom)
				(hide yes)
			)
		)
		(property "Datasheet" ""
			(at 113.03 264.16 0)
			(effects
				(font
					(size 1.27 1.27)
					(thickness 0.15)
				)
				(justify left bottom)
				(hide yes)
			)
		)
		(property "Description" ""
			(at 113.03 266.7 0)
			(effects
				(font
					(size 1.27 1.27)
				)
				(justify left bottom)
				(hide yes)
			)
		)
		(property "Author" "Antmicro"
			(at 113.03 259.08 0)
			(effects
				(font
					(size 1.27 1.27)
					(thickness 0.15)
				)
				(justify left bottom)
				(hide yes)
			)
		)
		(property "License" "Apache-2.0"
			(at 113.03 261.62 0)
			(effects
				(font
					(size 1.27 1.27)
					(thickness 0.15)
				)
				(justify left bottom)
				(hide yes)
			)
		)
		(pin "1"
		)
		(instances
			(project "sodimm-ddr5-tester"
				(path ""
					(reference "#PWR0205")
					(unit 1)
				)
			)
		)
	)
	(symbol
		(lib_id "antmicropower:GND")
		(at 284.48 90.805 0)
		(mirror y)
		(unit 1)
		(exclude_from_sim no)
		(in_bom yes)
		(on_board yes)
		(dnp no)
		(property "Reference" "#PWR0214"
			(at 284.48 97.155 0)
			(effects
				(font
					(size 1.27 1.27)
				)
				(hide yes)
			)
		)
		(property "Value" "GND"
			(at 282.448 94.742 0)
			(effects
				(font
					(size 1.27 1.27)
					(thickness 0.15)
				)
				(justify right)
			)
		)
		(property "Footprint" ""
			(at 275.59 98.425 0)
			(effects
				(font
					(size 1.27 1.27)
					(thickness 0.15)
				)
				(justify left bottom)
				(hide yes)
			)
		)
		(property "Datasheet" ""
			(at 275.59 103.505 0)
			(effects
				(font
					(size 1.27 1.27)
					(thickness 0.15)
				)
				(justify left bottom)
				(hide yes)
			)
		)
		(property "Description" ""
			(at 275.59 106.045 0)
			(effects
				(font
					(size 1.27 1.27)
				)
				(justify left bottom)
				(hide yes)
			)
		)
		(property "Author" "Antmicro"
			(at 275.59 98.425 0)
			(effects
				(font
					(size 1.27 1.27)
					(thickness 0.15)
				)
				(justify left bottom)
				(hide yes)
			)
		)
		(property "License" "Apache-2.0"
			(at 275.59 100.965 0)
			(effects
				(font
					(size 1.27 1.27)
					(thickness 0.15)
				)
				(justify left bottom)
				(hide yes)
			)
		)
		(pin "1"
		)
		(instances
			(project "sodimm-ddr5-tester"
				(path ""
					(reference "#PWR0214")
					(unit 1)
				)
			)
		)
	)
	(symbol
		(lib_id "antmicroCapacitors0402:C_100n_0402")
		(at 361.95 223.52 90)
		(unit 1)
		(exclude_from_sim no)
		(in_bom yes)
		(on_board yes)
		(dnp no)
		(fields_autoplaced yes)
		(property "Reference" "C10"
			(at 364.2741 220.143 90)
			(effects
				(font
					(size 1.27 1.27)
					(thickness 0.15)
				)
				(justify right)
			)
		)
		(property "Value" "C_100n_0402"
			(at 372.11 203.2 0)
			(effects
				(font
					(size 1.27 1.27)
					(thickness 0.15)
				)
				(justify left bottom)
				(hide yes)
			)
		)
		(property "Footprint" "antmicro-footprints:C_0402_1005Metric"
			(at 374.65 203.2 0)
			(effects
				(font
					(size 1.27 1.27)
					(thickness 0.15)
				)
				(justify left bottom)
				(hide yes)
			)
		)
		(property "Datasheet" "https://www.murata.com/products/productdetail?partno=GRM155R61H104KE14%23"
			(at 377.19 203.2 0)
			(effects
				(font
					(size 1.27 1.27)
					(thickness 0.15)
				)
				(justify left bottom)
				(hide yes)
			)
		)
		(property "Description" ""
			(at 361.95 223.52 0)
			(effects
				(font
					(size 1.27 1.27)
				)
			)
		)
		(property "MPN" "GRM155R61H104KE14D"
			(at 379.73 203.2 0)
			(effects
				(font
					(size 1.27 1.27)
					(thickness 0.15)
				)
				(justify left bottom)
				(hide yes)
			)
		)
		(property "Manufacturer" "Murata"
			(at 382.27 203.2 0)
			(effects
				(font
					(size 1.27 1.27)
					(thickness 0.15)
				)
				(justify left bottom)
				(hide yes)
			)
		)
		(property "License" "Apache-2.0"
			(at 384.81 203.2 0)
			(effects
				(font
					(size 1.27 1.27)
					(thickness 0.15)
				)
				(justify left bottom)
				(hide yes)
			)
		)
		(property "Author" "Antmicro"
			(at 387.35 203.2 0)
			(effects
				(font
					(size 1.27 1.27)
					(thickness 0.15)
				)
				(justify left bottom)
				(hide yes)
			)
		)
		(property "Val" "100n"
			(at 364.2741 222.6667 90)
			(effects
				(font
					(size 1.27 1.27)
					(thickness 0.15)
				)
				(justify right)
			)
		)
		(property "Voltage" "50V"
			(at 389.89 203.2 0)
			(effects
				(font
					(size 1.27 1.27)
				)
				(justify left bottom)
				(hide yes)
			)
		)
		(property "Dielectric" "X5R"
			(at 392.43 203.2 0)
			(effects
				(font
					(size 1.27 1.27)
				)
				(justify left bottom)
				(hide yes)
			)
		)
		(pin "1"
		)
		(pin "2"
		)
		(instances
			(project "sodimm-ddr5-tester"
				(path ""
					(reference "C10")
					(unit 1)
				)
			)
		)
	)
	(symbol
		(lib_id "antmicropower:GND")
		(at 353.695 138.43 0)
		(unit 1)
		(exclude_from_sim no)
		(in_bom yes)
		(on_board yes)
		(dnp no)
		(property "Reference" "#PWR038"
			(at 353.695 144.78 0)
			(effects
				(font
					(size 1.27 1.27)
				)
				(hide yes)
			)
		)
		(property "Value" "GND"
			(at 351.282 142.748 0)
			(effects
				(font
					(size 1.27 1.27)
					(thickness 0.15)
				)
				(justify left)
			)
		)
		(property "Footprint" ""
			(at 362.585 146.05 0)
			(effects
				(font
					(size 1.27 1.27)
					(thickness 0.15)
				)
				(justify left bottom)
				(hide yes)
			)
		)
		(property "Datasheet" ""
			(at 362.585 151.13 0)
			(effects
				(font
					(size 1.27 1.27)
					(thickness 0.15)
				)
				(justify left bottom)
				(hide yes)
			)
		)
		(property "Description" ""
			(at 362.585 153.67 0)
			(effects
				(font
					(size 1.27 1.27)
				)
				(justify left bottom)
				(hide yes)
			)
		)
		(property "Author" "Antmicro"
			(at 362.585 146.05 0)
			(effects
				(font
					(size 1.27 1.27)
					(thickness 0.15)
				)
				(justify left bottom)
				(hide yes)
			)
		)
		(property "License" "Apache-2.0"
			(at 362.585 148.59 0)
			(effects
				(font
					(size 1.27 1.27)
					(thickness 0.15)
				)
				(justify left bottom)
				(hide yes)
			)
		)
		(pin "1"
		)
		(instances
			(project "sodimm-ddr5-tester"
				(path ""
					(reference "#PWR038")
					(unit 1)
				)
			)
		)
	)
	(symbol
		(lib_id "antmicropower:GND")
		(at 267.97 60.325 0)
		(unit 1)
		(exclude_from_sim no)
		(in_bom yes)
		(on_board yes)
		(dnp no)
		(fields_autoplaced yes)
		(property "Reference" "#PWR036"
			(at 267.97 66.675 0)
			(effects
				(font
					(size 1.27 1.27)
				)
				(hide yes)
			)
		)
		(property "Value" "GND"
			(at 270.51 61.595 0)
			(effects
				(font
					(size 1.27 1.27)
					(thickness 0.15)
				)
				(justify left)
			)
		)
		(property "Footprint" ""
			(at 276.86 67.945 0)
			(effects
				(font
					(size 1.27 1.27)
					(thickness 0.15)
				)
				(justify left bottom)
				(hide yes)
			)
		)
		(property "Datasheet" ""
			(at 276.86 73.025 0)
			(effects
				(font
					(size 1.27 1.27)
					(thickness 0.15)
				)
				(justify left bottom)
				(hide yes)
			)
		)
		(property "Description" ""
			(at 276.86 75.565 0)
			(effects
				(font
					(size 1.27 1.27)
				)
				(justify left bottom)
				(hide yes)
			)
		)
		(property "Author" "Antmicro"
			(at 276.86 67.945 0)
			(effects
				(font
					(size 1.27 1.27)
					(thickness 0.15)
				)
				(justify left bottom)
				(hide yes)
			)
		)
		(property "License" "Apache-2.0"
			(at 276.86 70.485 0)
			(effects
				(font
					(size 1.27 1.27)
					(thickness 0.15)
				)
				(justify left bottom)
				(hide yes)
			)
		)
		(pin "1"
		)
		(instances
			(project "sodimm-ddr5-tester"
				(path ""
					(reference "#PWR036")
					(unit 1)
				)
			)
		)
	)
	(symbol
		(lib_id "antmicroResistors0402:R_0R_0402")
		(at 364.49 136.525 90)
		(unit 1)
		(exclude_from_sim no)
		(in_bom no)
		(on_board yes)
		(dnp yes)
		(fields_autoplaced yes)
		(property "Reference" "R32"
			(at 363.22 137.795 0)
			(effects
				(font
					(size 1.27 1.27)
					(thickness 0.15)
				)
			)
		)
		(property "Value" "R_0R_0402"
			(at 377.19 116.205 0)
			(effects
				(font
					(size 1.27 1.27)
					(thickness 0.15)
				)
				(justify left bottom)
				(hide yes)
			)
		)
		(property "Footprint" "antmicro-footprints:R_0402_1005Metric"
			(at 379.73 116.205 0)
			(effects
				(font
					(size 1.27 1.27)
					(thickness 0.15)
				)
				(justify left bottom)
				(hide yes)
			)
		)
		(property "Datasheet" "https://industrial.panasonic.com/cdbs/www-data/pdf/RDA0000/AOA0000C301.pdf"
			(at 382.27 116.205 0)
			(effects
				(font
					(size 1.27 1.27)
					(thickness 0.15)
				)
				(justify left bottom)
				(hide yes)
			)
		)
		(property "Description" ""
			(at 364.49 136.525 0)
			(effects
				(font
					(size 1.27 1.27)
				)
			)
		)
		(property "MPN" "ERJ2GE0R00X"
			(at 384.81 116.205 0)
			(effects
				(font
					(size 1.27 1.27)
					(thickness 0.15)
				)
				(justify left bottom)
				(hide yes)
			)
		)
		(property "Manufacturer" "Panasonic"
			(at 387.35 116.205 0)
			(effects
				(font
					(size 1.27 1.27)
					(thickness 0.15)
				)
				(justify left bottom)
				(hide yes)
			)
		)
		(property "License" "Apache-2.0"
			(at 389.89 116.205 0)
			(effects
				(font
					(size 1.27 1.27)
					(thickness 0.15)
				)
				(justify left bottom)
				(hide yes)
			)
		)
		(property "Author" "Antmicro"
			(at 392.43 116.205 0)
			(effects
				(font
					(size 1.27 1.27)
					(thickness 0.15)
				)
				(justify left bottom)
				(hide yes)
			)
		)
		(property "Val" "0R"
			(at 363.22 130.175 0)
			(effects
				(font
					(size 1.27 1.27)
					(thickness 0.15)
				)
			)
		)
		(property "Tolerance" "~"
			(at 374.65 116.205 0)
			(effects
				(font
					(size 1.27 1.27)
				)
				(justify left bottom)
				(hide yes)
			)
		)
		(property "Current" "1A"
			(at 394.97 116.205 0)
			(effects
				(font
					(size 1.27 1.27)
					(thickness 0.15)
				)
				(justify left bottom)
				(hide yes)
			)
		)
		(pin "1"
		)
		(pin "2"
		)
		(instances
			(project "sodimm-ddr5-tester"
				(path ""
					(reference "R32")
					(unit 1)
				)
			)
		)
	)
)
